FILE_TYPE = MACRO_DRAWING;
SET COLOR_WIRE YELLOW;
SET COLOR_PROP MONO;
SET COLOR_DOT WHITE;
SET COLOR_ARC YELLOW;
SET COLOR_BODY GREEN;
SET COLOR_NOTE MONO;
SET PROP_DISPLAY VALUE;
SET PAGE_NUMBER P44;
FORCEADD GND..1
(-2650 750);
FORCEPROP 3 LASTPIN (-2650 800) SIG_NAME GND\g
J 0
(-2640 810);
DISPLAY 0.659574 (-2640 810);
PAINT MONO (-2640 810);
DISPLAY INVISIBLE (-2640 810);
FORCEPROP 1 LAST VOLTAGE 0
J 0
(-2650 750);
PAINT SKYBLUE (-2650 750);
DISPLAY INVISIBLE (-2650 750);
FORCEPROP 2 LAST BOM_COST MEM
J 0
(-2650 755);
PAINT ORANGE (-2650 755);
DISPLAY INVISIBLE (-2650 755);
FORCEPROP 2 LAST CDS_LIB mstr_symbols
J 0
(-2650 750);
PAINT ORANGE (-2650 750);
DISPLAY INVISIBLE (-2650 750);
FORCEPROP 1 LAST SIZE 1B
J 0
(-2575 700);
DISPLAY 1.787234 (-2575 700);
PAINT GREEN (-2575 700);
DISPLAY INVISIBLE (-2575 700);
FORCEPROP 1 LAST BODY_TYPE PLUMBING
J 0
(-2695 707);
DISPLAY 0.340426 (-2695 707);
PAINT GREEN (-2695 707);
DISPLAY INVISIBLE (-2695 707);
FORCEPROP 1 LAST PATH I1
J 0
(-2575 750);
DISPLAY 0.872340 (-2575 750);
PAINT AQUA (-2575 750);
DISPLAY INVISIBLE (-2575 750);
FORCEPROP 2 LAST ROOM DDR4_CH_A
J 0
(-2650 755);
PAINT ORANGE (-2650 755);
DISPLAY INVISIBLE (-2650 755);
FORCEPROP 1 LAST HDL_POWER GND
J 0
(-2650 900);
DISPLAY 1.404255 (-2650 900);
PAINT GREEN (-2650 900);
DISPLAY INVISIBLE (-2650 900);
FORCEADD OFFPAGE..6
(-2100 1350);
FORCEPROP 2 LASTPIN (-2050 1350) SIG_NAME SMB_DDR_ABC_VPP_SDA
J 0
(-2010 1360);
DISPLAY 0.617021 (-2010 1360);
PAINT ORANGE (-2010 1360);
FORCEPROP 2 LAST $XR5 99 
J 0
(-2829 1350);
DISPLAY 0.638298 (-2829 1350);
PAINT MONO (-2829 1350);
FORCEPROP 2 LAST $XR4 48 
J 0
(-2739 1350);
DISPLAY 0.638298 (-2739 1350);
PAINT MONO (-2739 1350);
FORCEPROP 2 LAST $XR3 47 
J 0
(-2649 1350);
DISPLAY 0.638298 (-2649 1350);
PAINT MONO (-2649 1350);
FORCEPROP 2 LAST $XR2 46 
J 0
(-2559 1350);
DISPLAY 0.638298 (-2559 1350);
PAINT MONO (-2559 1350);
FORCEPROP 2 LAST $XR1 45 
J 0
(-2469 1350);
DISPLAY 0.638298 (-2469 1350);
PAINT MONO (-2469 1350);
FORCEPROP 2 LAST $XR0 43 
J 0
(-2379 1350);
DISPLAY 0.638298 (-2379 1350);
PAINT MONO (-2379 1350);
FORCEPROP 2 LAST CDS_LIB mstr_standard
J 0
(-2100 1350);
DISPLAY 0.787234 (-2100 1350);
PAINT MONO (-2100 1350);
DISPLAY INVISIBLE (-2100 1350);
FORCEPROP 1 LAST OFFPAGE TRUE
J 0
(-1775 1225);
DISPLAY 0.936170 (-1775 1225);
PAINT GREEN (-1775 1225);
DISPLAY INVISIBLE (-1775 1225);
FORCEPROP 1 LAST COMMENT_BODY TRUE
J 0
(-2000 1275);
DISPLAY 0.936170 (-2000 1275);
PAINT GREEN (-2000 1275);
DISPLAY INVISIBLE (-2000 1275);
FORCEPROP 2 LAST PATH I10
J 0
(-2375 1400);
DISPLAY 1.021277 (-2375 1400);
PAINT ORANGE (-2375 1400);
DISPLAY INVISIBLE (-2375 1400);
FORCEADD TAP..6
R 2
(100 3150);
FORCEPROP 3 LASTPIN (50 3150) SIG_NAME M_A_DQ<39>
J 0
(60 3160);
DISPLAY 0.659574 (60 3160);
PAINT MONO (60 3160);
DISPLAY INVISIBLE (60 3160);
FORCEPROP 1 LASTPIN (50 3150) BN 39
J 2
(100 3160);
DISPLAY 0.617021 (100 3160);
PAINT PINK (100 3160);
FORCEPROP 2 LAST CDS_LIB mstr_standard
J 2
(100 3150);
DISPLAY 0.787234 (100 3150);
PAINT MONO (100 3150);
DISPLAY INVISIBLE (100 3150);
FORCEPROP 1 LAST BODY_TYPE PLUMBING
J 2
(100 3100);
DISPLAY 1.234043 (100 3100);
PAINT GREEN (100 3100);
DISPLAY INVISIBLE (100 3100);
FORCEPROP 1 LAST HDL_TAP TRUE
J 2
(-225 3025);
DISPLAY 1.234043 (-225 3025);
PAINT GREEN (-225 3025);
DISPLAY INVISIBLE (-225 3025);
FORCEPROP 1 LAST PATH I100
J 2
(102 3150);
DISPLAY 0.872340 (102 3150);
PAINT GREEN (102 3150);
DISPLAY INVISIBLE (102 3150);
FORCEADD TAP..6
R 2
(100 3200);
FORCEPROP 3 LASTPIN (50 3200) SIG_NAME M_A_DQ<40>
J 0
(60 3210);
DISPLAY 0.659574 (60 3210);
PAINT MONO (60 3210);
DISPLAY INVISIBLE (60 3210);
FORCEPROP 1 LASTPIN (50 3200) BN 40
J 2
(100 3210);
DISPLAY 0.617021 (100 3210);
PAINT PINK (100 3210);
FORCEPROP 2 LAST CDS_LIB mstr_standard
J 2
(100 3200);
DISPLAY 0.787234 (100 3200);
PAINT MONO (100 3200);
DISPLAY INVISIBLE (100 3200);
FORCEPROP 1 LAST BODY_TYPE PLUMBING
J 2
(100 3150);
DISPLAY 1.234043 (100 3150);
PAINT GREEN (100 3150);
DISPLAY INVISIBLE (100 3150);
FORCEPROP 1 LAST HDL_TAP TRUE
J 2
(-225 3075);
DISPLAY 1.234043 (-225 3075);
PAINT GREEN (-225 3075);
DISPLAY INVISIBLE (-225 3075);
FORCEPROP 1 LAST PATH I101
J 2
(102 3200);
DISPLAY 0.872340 (102 3200);
PAINT GREEN (102 3200);
DISPLAY INVISIBLE (102 3200);
FORCEADD TAP..6
R 2
(100 3250);
FORCEPROP 3 LASTPIN (50 3250) SIG_NAME M_A_DQ<41>
J 0
(60 3260);
DISPLAY 0.659574 (60 3260);
PAINT MONO (60 3260);
DISPLAY INVISIBLE (60 3260);
FORCEPROP 1 LASTPIN (50 3250) BN 41
J 2
(100 3260);
DISPLAY 0.617021 (100 3260);
PAINT PINK (100 3260);
FORCEPROP 2 LAST CDS_LIB mstr_standard
J 2
(100 3250);
DISPLAY 0.787234 (100 3250);
PAINT MONO (100 3250);
DISPLAY INVISIBLE (100 3250);
FORCEPROP 1 LAST BODY_TYPE PLUMBING
J 2
(100 3200);
DISPLAY 1.234043 (100 3200);
PAINT GREEN (100 3200);
DISPLAY INVISIBLE (100 3200);
FORCEPROP 1 LAST HDL_TAP TRUE
J 2
(-225 3125);
DISPLAY 1.234043 (-225 3125);
PAINT GREEN (-225 3125);
DISPLAY INVISIBLE (-225 3125);
FORCEPROP 1 LAST PATH I102
J 2
(102 3250);
DISPLAY 0.872340 (102 3250);
PAINT GREEN (102 3250);
DISPLAY INVISIBLE (102 3250);
FORCEADD TAP..6
R 2
(100 3300);
FORCEPROP 3 LASTPIN (50 3300) SIG_NAME M_A_DQ<42>
J 0
(60 3310);
DISPLAY 0.659574 (60 3310);
PAINT MONO (60 3310);
DISPLAY INVISIBLE (60 3310);
FORCEPROP 1 LASTPIN (50 3300) BN 42
J 2
(100 3310);
DISPLAY 0.617021 (100 3310);
PAINT PINK (100 3310);
FORCEPROP 2 LAST CDS_LIB mstr_standard
J 2
(100 3300);
DISPLAY 0.787234 (100 3300);
PAINT MONO (100 3300);
DISPLAY INVISIBLE (100 3300);
FORCEPROP 1 LAST BODY_TYPE PLUMBING
J 2
(100 3250);
DISPLAY 1.234043 (100 3250);
PAINT GREEN (100 3250);
DISPLAY INVISIBLE (100 3250);
FORCEPROP 1 LAST HDL_TAP TRUE
J 2
(-225 3175);
DISPLAY 1.234043 (-225 3175);
PAINT GREEN (-225 3175);
DISPLAY INVISIBLE (-225 3175);
FORCEPROP 1 LAST PATH I103
J 2
(102 3300);
DISPLAY 0.872340 (102 3300);
PAINT GREEN (102 3300);
DISPLAY INVISIBLE (102 3300);
FORCEADD TAP..6
R 2
(100 3400);
FORCEPROP 3 LASTPIN (50 3400) SIG_NAME M_A_DQ<44>
J 0
(60 3410);
DISPLAY 0.659574 (60 3410);
PAINT MONO (60 3410);
DISPLAY INVISIBLE (60 3410);
FORCEPROP 1 LASTPIN (50 3400) BN 44
J 2
(100 3410);
DISPLAY 0.617021 (100 3410);
PAINT PINK (100 3410);
FORCEPROP 2 LAST CDS_LIB mstr_standard
J 2
(100 3400);
DISPLAY 0.787234 (100 3400);
PAINT MONO (100 3400);
DISPLAY INVISIBLE (100 3400);
FORCEPROP 1 LAST BODY_TYPE PLUMBING
J 2
(100 3350);
DISPLAY 1.234043 (100 3350);
PAINT GREEN (100 3350);
DISPLAY INVISIBLE (100 3350);
FORCEPROP 1 LAST HDL_TAP TRUE
J 2
(-225 3275);
DISPLAY 1.234043 (-225 3275);
PAINT GREEN (-225 3275);
DISPLAY INVISIBLE (-225 3275);
FORCEPROP 1 LAST PATH I104
J 2
(102 3400);
DISPLAY 0.872340 (102 3400);
PAINT GREEN (102 3400);
DISPLAY INVISIBLE (102 3400);
FORCEADD TAP..6
R 2
(100 3350);
FORCEPROP 3 LASTPIN (50 3350) SIG_NAME M_A_DQ<43>
J 0
(60 3360);
DISPLAY 0.659574 (60 3360);
PAINT MONO (60 3360);
DISPLAY INVISIBLE (60 3360);
FORCEPROP 1 LASTPIN (50 3350) BN 43
J 2
(100 3360);
DISPLAY 0.617021 (100 3360);
PAINT PINK (100 3360);
FORCEPROP 2 LAST CDS_LIB mstr_standard
J 2
(100 3350);
DISPLAY 0.787234 (100 3350);
PAINT MONO (100 3350);
DISPLAY INVISIBLE (100 3350);
FORCEPROP 1 LAST BODY_TYPE PLUMBING
J 2
(100 3300);
DISPLAY 1.234043 (100 3300);
PAINT GREEN (100 3300);
DISPLAY INVISIBLE (100 3300);
FORCEPROP 1 LAST HDL_TAP TRUE
J 2
(-225 3225);
DISPLAY 1.234043 (-225 3225);
PAINT GREEN (-225 3225);
DISPLAY INVISIBLE (-225 3225);
FORCEPROP 1 LAST PATH I105
J 2
(102 3350);
DISPLAY 0.872340 (102 3350);
PAINT GREEN (102 3350);
DISPLAY INVISIBLE (102 3350);
FORCEADD TAP..6
R 2
(100 3450);
FORCEPROP 3 LASTPIN (50 3450) SIG_NAME M_A_DQ<45>
J 0
(60 3460);
DISPLAY 0.659574 (60 3460);
PAINT MONO (60 3460);
DISPLAY INVISIBLE (60 3460);
FORCEPROP 1 LASTPIN (50 3450) BN 45
J 2
(100 3460);
DISPLAY 0.617021 (100 3460);
PAINT PINK (100 3460);
FORCEPROP 2 LAST CDS_LIB mstr_standard
J 2
(100 3450);
DISPLAY 0.787234 (100 3450);
PAINT MONO (100 3450);
DISPLAY INVISIBLE (100 3450);
FORCEPROP 1 LAST BODY_TYPE PLUMBING
J 2
(100 3400);
DISPLAY 1.234043 (100 3400);
PAINT GREEN (100 3400);
DISPLAY INVISIBLE (100 3400);
FORCEPROP 1 LAST HDL_TAP TRUE
J 2
(-225 3325);
DISPLAY 1.234043 (-225 3325);
PAINT GREEN (-225 3325);
DISPLAY INVISIBLE (-225 3325);
FORCEPROP 1 LAST PATH I106
J 2
(102 3450);
DISPLAY 0.872340 (102 3450);
PAINT GREEN (102 3450);
DISPLAY INVISIBLE (102 3450);
FORCEADD TAP..6
R 2
(100 3500);
FORCEPROP 3 LASTPIN (50 3500) SIG_NAME M_A_DQ<46>
J 0
(60 3510);
DISPLAY 0.659574 (60 3510);
PAINT MONO (60 3510);
DISPLAY INVISIBLE (60 3510);
FORCEPROP 1 LASTPIN (50 3500) BN 46
J 2
(100 3510);
DISPLAY 0.617021 (100 3510);
PAINT PINK (100 3510);
FORCEPROP 2 LAST CDS_LIB mstr_standard
J 2
(100 3500);
DISPLAY 0.787234 (100 3500);
PAINT MONO (100 3500);
DISPLAY INVISIBLE (100 3500);
FORCEPROP 1 LAST BODY_TYPE PLUMBING
J 2
(100 3450);
DISPLAY 1.234043 (100 3450);
PAINT GREEN (100 3450);
DISPLAY INVISIBLE (100 3450);
FORCEPROP 1 LAST HDL_TAP TRUE
J 2
(-225 3375);
DISPLAY 1.234043 (-225 3375);
PAINT GREEN (-225 3375);
DISPLAY INVISIBLE (-225 3375);
FORCEPROP 1 LAST PATH I107
J 2
(102 3500);
DISPLAY 0.872340 (102 3500);
PAINT GREEN (102 3500);
DISPLAY INVISIBLE (102 3500);
FORCEADD TAP..6
R 2
(100 3650);
FORCEPROP 3 LASTPIN (50 3650) SIG_NAME M_A_DQ<49>
J 0
(60 3660);
DISPLAY 0.659574 (60 3660);
PAINT MONO (60 3660);
DISPLAY INVISIBLE (60 3660);
FORCEPROP 1 LASTPIN (50 3650) BN 49
J 2
(100 3660);
DISPLAY 0.617021 (100 3660);
PAINT PINK (100 3660);
FORCEPROP 2 LAST CDS_LIB mstr_standard
J 2
(100 3650);
DISPLAY 0.787234 (100 3650);
PAINT MONO (100 3650);
DISPLAY INVISIBLE (100 3650);
FORCEPROP 1 LAST BODY_TYPE PLUMBING
J 2
(100 3600);
DISPLAY 1.234043 (100 3600);
PAINT GREEN (100 3600);
DISPLAY INVISIBLE (100 3600);
FORCEPROP 1 LAST HDL_TAP TRUE
J 2
(-225 3525);
DISPLAY 1.234043 (-225 3525);
PAINT GREEN (-225 3525);
DISPLAY INVISIBLE (-225 3525);
FORCEPROP 1 LAST PATH I108
J 2
(102 3650);
DISPLAY 0.872340 (102 3650);
PAINT GREEN (102 3650);
DISPLAY INVISIBLE (102 3650);
FORCEADD TAP..6
R 2
(100 3600);
FORCEPROP 3 LASTPIN (50 3600) SIG_NAME M_A_DQ<48>
J 0
(60 3610);
DISPLAY 0.659574 (60 3610);
PAINT MONO (60 3610);
DISPLAY INVISIBLE (60 3610);
FORCEPROP 1 LASTPIN (50 3600) BN 48
J 2
(100 3610);
DISPLAY 0.617021 (100 3610);
PAINT PINK (100 3610);
FORCEPROP 2 LAST CDS_LIB mstr_standard
J 2
(100 3600);
DISPLAY 0.787234 (100 3600);
PAINT MONO (100 3600);
DISPLAY INVISIBLE (100 3600);
FORCEPROP 1 LAST BODY_TYPE PLUMBING
J 2
(100 3550);
DISPLAY 1.234043 (100 3550);
PAINT GREEN (100 3550);
DISPLAY INVISIBLE (100 3550);
FORCEPROP 1 LAST HDL_TAP TRUE
J 2
(-225 3475);
DISPLAY 1.234043 (-225 3475);
PAINT GREEN (-225 3475);
DISPLAY INVISIBLE (-225 3475);
FORCEPROP 1 LAST PATH I109
J 2
(102 3600);
DISPLAY 0.872340 (102 3600);
PAINT GREEN (102 3600);
DISPLAY INVISIBLE (102 3600);
FORCEADD OFFPAGE..1
(-2100 1300);
FORCEPROP 2 LAST $XR5 48 
J 0
(-2831 1300);
DISPLAY 0.638298 (-2831 1300);
PAINT MONO (-2831 1300);
FORCEPROP 2 LAST $XR4 47 
J 0
(-2741 1300);
DISPLAY 0.638298 (-2741 1300);
PAINT MONO (-2741 1300);
FORCEPROP 2 LAST $XR3 46 
J 0
(-2651 1300);
DISPLAY 0.638298 (-2651 1300);
PAINT MONO (-2651 1300);
FORCEPROP 2 LAST $XR2 45 
J 0
(-2561 1300);
DISPLAY 0.638298 (-2561 1300);
PAINT MONO (-2561 1300);
FORCEPROP 2 LAST $XR1 43 
J 0
(-2471 1300);
DISPLAY 0.638298 (-2471 1300);
PAINT MONO (-2471 1300);
FORCEPROP 2 LAST $XR0 99 
J 0
(-2381 1300);
DISPLAY 0.638298 (-2381 1300);
PAINT MONO (-2381 1300);
FORCEPROP 2 LAST CDS_LIB mstr_standard
J 0
(-2100 1300);
DISPLAY 0.787234 (-2100 1300);
PAINT MONO (-2100 1300);
DISPLAY INVISIBLE (-2100 1300);
FORCEPROP 1 LAST OFFPAGE TRUE
J 0
(-1775 1175);
DISPLAY 0.936170 (-1775 1175);
PAINT GREEN (-1775 1175);
DISPLAY INVISIBLE (-1775 1175);
FORCEPROP 1 LAST COMMENT_BODY TRUE
J 0
(-1975 1200);
DISPLAY 0.936170 (-1975 1200);
PAINT GREEN (-1975 1200);
DISPLAY INVISIBLE (-1975 1200);
FORCEPROP 2 LAST PATH I11
J 0
(-2375 1350);
DISPLAY 1.021277 (-2375 1350);
PAINT ORANGE (-2375 1350);
DISPLAY INVISIBLE (-2375 1350);
FORCEADD TAP..6
R 2
(100 3550);
FORCEPROP 3 LASTPIN (50 3550) SIG_NAME M_A_DQ<47>
J 0
(60 3560);
DISPLAY 0.659574 (60 3560);
PAINT MONO (60 3560);
DISPLAY INVISIBLE (60 3560);
FORCEPROP 1 LASTPIN (50 3550) BN 47
J 2
(100 3560);
DISPLAY 0.617021 (100 3560);
PAINT PINK (100 3560);
FORCEPROP 2 LAST CDS_LIB mstr_standard
J 2
(100 3550);
DISPLAY 0.787234 (100 3550);
PAINT MONO (100 3550);
DISPLAY INVISIBLE (100 3550);
FORCEPROP 1 LAST BODY_TYPE PLUMBING
J 2
(100 3500);
DISPLAY 1.234043 (100 3500);
PAINT GREEN (100 3500);
DISPLAY INVISIBLE (100 3500);
FORCEPROP 1 LAST HDL_TAP TRUE
J 2
(-225 3425);
DISPLAY 1.234043 (-225 3425);
PAINT GREEN (-225 3425);
DISPLAY INVISIBLE (-225 3425);
FORCEPROP 1 LAST PATH I110
J 2
(102 3550);
DISPLAY 0.872340 (102 3550);
PAINT GREEN (102 3550);
DISPLAY INVISIBLE (102 3550);
FORCEADD TAP..6
R 2
(100 3700);
FORCEPROP 3 LASTPIN (50 3700) SIG_NAME M_A_DQ<50>
J 0
(60 3710);
DISPLAY 0.659574 (60 3710);
PAINT MONO (60 3710);
DISPLAY INVISIBLE (60 3710);
FORCEPROP 1 LASTPIN (50 3700) BN 50
J 2
(100 3710);
DISPLAY 0.617021 (100 3710);
PAINT PINK (100 3710);
FORCEPROP 2 LAST CDS_LIB mstr_standard
J 2
(100 3700);
DISPLAY 0.787234 (100 3700);
PAINT MONO (100 3700);
DISPLAY INVISIBLE (100 3700);
FORCEPROP 1 LAST BODY_TYPE PLUMBING
J 2
(100 3650);
DISPLAY 1.234043 (100 3650);
PAINT GREEN (100 3650);
DISPLAY INVISIBLE (100 3650);
FORCEPROP 1 LAST HDL_TAP TRUE
J 2
(-225 3575);
DISPLAY 1.234043 (-225 3575);
PAINT GREEN (-225 3575);
DISPLAY INVISIBLE (-225 3575);
FORCEPROP 1 LAST PATH I111
J 2
(102 3700);
DISPLAY 0.872340 (102 3700);
PAINT GREEN (102 3700);
DISPLAY INVISIBLE (102 3700);
FORCEADD TAP..6
R 2
(100 3750);
FORCEPROP 3 LASTPIN (50 3750) SIG_NAME M_A_DQ<51>
J 0
(60 3760);
DISPLAY 0.659574 (60 3760);
PAINT MONO (60 3760);
DISPLAY INVISIBLE (60 3760);
FORCEPROP 1 LASTPIN (50 3750) BN 51
J 2
(100 3760);
DISPLAY 0.617021 (100 3760);
PAINT PINK (100 3760);
FORCEPROP 2 LAST CDS_LIB mstr_standard
J 2
(100 3750);
DISPLAY 0.787234 (100 3750);
PAINT MONO (100 3750);
DISPLAY INVISIBLE (100 3750);
FORCEPROP 1 LAST BODY_TYPE PLUMBING
J 2
(100 3700);
DISPLAY 1.234043 (100 3700);
PAINT GREEN (100 3700);
DISPLAY INVISIBLE (100 3700);
FORCEPROP 1 LAST HDL_TAP TRUE
J 2
(-225 3625);
DISPLAY 1.234043 (-225 3625);
PAINT GREEN (-225 3625);
DISPLAY INVISIBLE (-225 3625);
FORCEPROP 1 LAST PATH I112
J 2
(102 3750);
DISPLAY 0.872340 (102 3750);
PAINT GREEN (102 3750);
DISPLAY INVISIBLE (102 3750);
FORCEADD TAP..6
R 2
(100 3850);
FORCEPROP 3 LASTPIN (50 3850) SIG_NAME M_A_DQ<53>
J 0
(60 3860);
DISPLAY 0.659574 (60 3860);
PAINT MONO (60 3860);
DISPLAY INVISIBLE (60 3860);
FORCEPROP 1 LASTPIN (50 3850) BN 53
J 2
(100 3860);
DISPLAY 0.617021 (100 3860);
PAINT PINK (100 3860);
FORCEPROP 2 LAST CDS_LIB mstr_standard
J 2
(100 3850);
DISPLAY 0.787234 (100 3850);
PAINT MONO (100 3850);
DISPLAY INVISIBLE (100 3850);
FORCEPROP 1 LAST BODY_TYPE PLUMBING
J 2
(100 3800);
DISPLAY 1.234043 (100 3800);
PAINT GREEN (100 3800);
DISPLAY INVISIBLE (100 3800);
FORCEPROP 1 LAST HDL_TAP TRUE
J 2
(-225 3725);
DISPLAY 1.234043 (-225 3725);
PAINT GREEN (-225 3725);
DISPLAY INVISIBLE (-225 3725);
FORCEPROP 1 LAST PATH I113
J 2
(102 3850);
DISPLAY 0.872340 (102 3850);
PAINT GREEN (102 3850);
DISPLAY INVISIBLE (102 3850);
FORCEADD TAP..6
R 2
(100 3800);
FORCEPROP 3 LASTPIN (50 3800) SIG_NAME M_A_DQ<52>
J 0
(60 3810);
DISPLAY 0.659574 (60 3810);
PAINT MONO (60 3810);
DISPLAY INVISIBLE (60 3810);
FORCEPROP 1 LASTPIN (50 3800) BN 52
J 2
(100 3810);
DISPLAY 0.617021 (100 3810);
PAINT PINK (100 3810);
FORCEPROP 2 LAST CDS_LIB mstr_standard
J 2
(100 3800);
DISPLAY 0.787234 (100 3800);
PAINT MONO (100 3800);
DISPLAY INVISIBLE (100 3800);
FORCEPROP 1 LAST BODY_TYPE PLUMBING
J 2
(100 3750);
DISPLAY 1.234043 (100 3750);
PAINT GREEN (100 3750);
DISPLAY INVISIBLE (100 3750);
FORCEPROP 1 LAST HDL_TAP TRUE
J 2
(-225 3675);
DISPLAY 1.234043 (-225 3675);
PAINT GREEN (-225 3675);
DISPLAY INVISIBLE (-225 3675);
FORCEPROP 1 LAST PATH I114
J 2
(102 3800);
DISPLAY 0.872340 (102 3800);
PAINT GREEN (102 3800);
DISPLAY INVISIBLE (102 3800);
FORCEADD TAP..6
R 2
(100 3900);
FORCEPROP 3 LASTPIN (50 3900) SIG_NAME M_A_DQ<54>
J 0
(60 3910);
DISPLAY 0.659574 (60 3910);
PAINT MONO (60 3910);
DISPLAY INVISIBLE (60 3910);
FORCEPROP 1 LASTPIN (50 3900) BN 54
J 2
(100 3910);
DISPLAY 0.617021 (100 3910);
PAINT PINK (100 3910);
FORCEPROP 2 LAST CDS_LIB mstr_standard
J 2
(100 3900);
DISPLAY 0.787234 (100 3900);
PAINT MONO (100 3900);
DISPLAY INVISIBLE (100 3900);
FORCEPROP 1 LAST BODY_TYPE PLUMBING
J 2
(100 3850);
DISPLAY 1.234043 (100 3850);
PAINT GREEN (100 3850);
DISPLAY INVISIBLE (100 3850);
FORCEPROP 1 LAST HDL_TAP TRUE
J 2
(-225 3775);
DISPLAY 1.234043 (-225 3775);
PAINT GREEN (-225 3775);
DISPLAY INVISIBLE (-225 3775);
FORCEPROP 1 LAST PATH I115
J 2
(102 3900);
DISPLAY 0.872340 (102 3900);
PAINT GREEN (102 3900);
DISPLAY INVISIBLE (102 3900);
FORCEADD TAP..6
R 2
(100 3950);
FORCEPROP 3 LASTPIN (50 3950) SIG_NAME M_A_DQ<55>
J 0
(60 3960);
DISPLAY 0.659574 (60 3960);
PAINT MONO (60 3960);
DISPLAY INVISIBLE (60 3960);
FORCEPROP 1 LASTPIN (50 3950) BN 55
J 2
(100 3960);
DISPLAY 0.617021 (100 3960);
PAINT PINK (100 3960);
FORCEPROP 2 LAST CDS_LIB mstr_standard
J 2
(100 3950);
DISPLAY 0.787234 (100 3950);
PAINT MONO (100 3950);
DISPLAY INVISIBLE (100 3950);
FORCEPROP 1 LAST BODY_TYPE PLUMBING
J 2
(100 3900);
DISPLAY 1.234043 (100 3900);
PAINT GREEN (100 3900);
DISPLAY INVISIBLE (100 3900);
FORCEPROP 1 LAST HDL_TAP TRUE
J 2
(-225 3825);
DISPLAY 1.234043 (-225 3825);
PAINT GREEN (-225 3825);
DISPLAY INVISIBLE (-225 3825);
FORCEPROP 1 LAST PATH I116
J 2
(102 3950);
DISPLAY 0.872340 (102 3950);
PAINT GREEN (102 3950);
DISPLAY INVISIBLE (102 3950);
FORCEADD TAP..6
R 2
(100 4000);
FORCEPROP 3 LASTPIN (50 4000) SIG_NAME M_A_DQ<56>
J 0
(60 4010);
DISPLAY 0.659574 (60 4010);
PAINT MONO (60 4010);
DISPLAY INVISIBLE (60 4010);
FORCEPROP 1 LASTPIN (50 4000) BN 56
J 2
(100 4010);
DISPLAY 0.617021 (100 4010);
PAINT PINK (100 4010);
FORCEPROP 2 LAST CDS_LIB mstr_standard
J 2
(100 4000);
DISPLAY 0.787234 (100 4000);
PAINT MONO (100 4000);
DISPLAY INVISIBLE (100 4000);
FORCEPROP 1 LAST BODY_TYPE PLUMBING
J 2
(100 3950);
DISPLAY 1.234043 (100 3950);
PAINT GREEN (100 3950);
DISPLAY INVISIBLE (100 3950);
FORCEPROP 1 LAST HDL_TAP TRUE
J 2
(-225 3875);
DISPLAY 1.234043 (-225 3875);
PAINT GREEN (-225 3875);
DISPLAY INVISIBLE (-225 3875);
FORCEPROP 1 LAST PATH I117
J 2
(102 4000);
DISPLAY 0.872340 (102 4000);
PAINT GREEN (102 4000);
DISPLAY INVISIBLE (102 4000);
FORCEADD PVTT_ABC..1
(800 2350);
FORCEPROP 3 LASTPIN (800 2300) SIG_NAME PVTT_ABC\g
J 0
(810 2310);
DISPLAY 0.659574 (810 2310);
PAINT MONO (810 2310);
DISPLAY INVISIBLE (810 2310);
FORCEPROP 1 LAST VOLTAGE 0.6V
J 0
(755 2307);
DISPLAY 0.340426 (755 2307);
PAINT SKYBLUE (755 2307);
DISPLAY INVISIBLE (755 2307);
FORCEPROP 2 LAST BOM_COST MEM
J 0
(800 2355);
PAINT ORANGE (800 2355);
DISPLAY INVISIBLE (800 2355);
FORCEPROP 2 LAST CDS_LIB mstr_symbols
J 0
(800 2350);
PAINT ORANGE (800 2350);
DISPLAY INVISIBLE (800 2350);
FORCEPROP 1 LAST BODY_TYPE PLUMBING
J 0
(755 2307);
DISPLAY 0.340426 (755 2307);
PAINT GREEN (755 2307);
DISPLAY INVISIBLE (755 2307);
FORCEPROP 1 LAST PATH I118
J 0
(850 2375);
DISPLAY 0.872340 (850 2375);
PAINT AQUA (850 2375);
DISPLAY INVISIBLE (850 2375);
FORCEPROP 2 LAST ROOM DDR4_CH_A
J 0
(800 2355);
PAINT ORANGE (800 2355);
DISPLAY INVISIBLE (800 2355);
FORCEPROP 1 LAST HDL_POWER PVTT_ABC
J 1
(800 2400);
DISPLAY 0.872340 (800 2400);
PAINT GREEN (800 2400);
DISPLAY INVISIBLE (800 2400);
FORCEADD PVPP_ABC..1
(950 2650);
FORCEPROP 3 LASTPIN (950 2600) SIG_NAME PVPP_ABC\g
J 0
(960 2610);
DISPLAY 0.659574 (960 2610);
PAINT MONO (960 2610);
DISPLAY INVISIBLE (960 2610);
FORCEPROP 1 LAST VOLTAGE 2.5V
J 0
(905 2607);
DISPLAY 0.340426 (905 2607);
PAINT SKYBLUE (905 2607);
DISPLAY INVISIBLE (905 2607);
FORCEPROP 0 LAST BOM_COST MEM
J 0
(950 2750);
PAINT ORANGE (950 2750);
DISPLAY INVISIBLE (950 2750);
FORCEPROP 2 LAST CDS_LIB mstr_symbols
J 0
(950 2650);
PAINT ORANGE (950 2650);
DISPLAY INVISIBLE (950 2650);
FORCEPROP 1 LAST BODY_TYPE PLUMBING
J 0
(905 2607);
DISPLAY 0.340426 (905 2607);
PAINT GREEN (905 2607);
DISPLAY INVISIBLE (905 2607);
FORCEPROP 1 LAST PATH I119
J 0
(1000 2675);
DISPLAY 0.872340 (1000 2675);
PAINT AQUA (1000 2675);
DISPLAY INVISIBLE (1000 2675);
FORCEPROP 2 LAST ROOM DDR4_CH_A
J 0
(950 2750);
PAINT ORANGE (950 2750);
DISPLAY INVISIBLE (950 2750);
FORCEPROP 1 LAST HDL_POWER PVPP_ABC
J 1
(950 2700);
DISPLAY 0.872340 (950 2700);
PAINT GREEN (950 2700);
DISPLAY INVISIBLE (950 2700);
FORCEADD TAP..6
(-1450 1950);
FORCEPROP 3 LASTPIN (-1400 1950) SIG_NAME M_A_ECC<0>
J 0
(-1390 1960);
DISPLAY 0.659574 (-1390 1960);
PAINT MONO (-1390 1960);
DISPLAY INVISIBLE (-1390 1960);
FORCEPROP 1 LASTPIN (-1400 1950) BN 0
J 0
(-1450 1960);
DISPLAY 0.617021 (-1450 1960);
PAINT PINK (-1450 1960);
FORCEPROP 2 LAST CDS_LIB mstr_standard
J 0
(-1450 1950);
DISPLAY 0.787234 (-1450 1950);
PAINT MONO (-1450 1950);
DISPLAY INVISIBLE (-1450 1950);
FORCEPROP 1 LAST BODY_TYPE PLUMBING
J 0
(-1450 1900);
DISPLAY 1.234043 (-1450 1900);
PAINT GREEN (-1450 1900);
DISPLAY INVISIBLE (-1450 1900);
FORCEPROP 1 LAST HDL_TAP TRUE
J 0
(-1125 1825);
DISPLAY 1.234043 (-1125 1825);
PAINT GREEN (-1125 1825);
DISPLAY INVISIBLE (-1125 1825);
FORCEPROP 1 LAST PATH I12
J 0
(-1452 1950);
DISPLAY 0.872340 (-1452 1950);
PAINT GREEN (-1452 1950);
DISPLAY INVISIBLE (-1452 1950);
FORCEADD SCONN288_H44441003..2
(1650 4000);
FORCEPROP 1 LAST LOCATION J6T1
J 0
(1250 5100);
DISPLAY 0.617021 (1250 5100);
PAINT AQUA (1250 5100);
FORCEPROP 1 LAST PART_NUMBER H44441-003
J 0
(1250 2900);
DISPLAY 0.617021 (1250 2900);
PAINT BLUE (1250 2900);
FORCEPROP 1 LAST MATERIAL SCONN
J 0
(1250 5050);
DISPLAY 0.617021 (1250 5050);
PAINT SKYBLUE (1250 5050);
FORCEPROP 2 LASTPIN (2100 4850) $PN 51
J 0
(2110 4860);
DISPLAY 0.617021 (2110 4860);
PAINT ORANGE (2110 4860);
FORCEPROP 2 LASTPIN (2100 4800) $PN 52
J 0
(2110 4810);
DISPLAY 0.617021 (2110 4810);
PAINT ORANGE (2110 4810);
FORCEPROP 2 LASTPIN (2100 4700) $PN 133
J 0
(2110 4710);
DISPLAY 0.617021 (2110 4710);
PAINT ORANGE (2110 4710);
FORCEPROP 2 LASTPIN (2100 4650) $PN 121
J 0
(2110 4660);
DISPLAY 0.617021 (2110 4660);
PAINT ORANGE (2110 4660);
FORCEPROP 2 LASTPIN (2100 4600) $PN 122
J 0
(2110 4610);
DISPLAY 0.617021 (2110 4610);
PAINT ORANGE (2110 4610);
FORCEPROP 2 LASTPIN (2100 4550) $PN 110
J 0
(2110 4560);
DISPLAY 0.617021 (2110 4560);
PAINT ORANGE (2110 4560);
FORCEPROP 2 LASTPIN (2100 4500) $PN 111
J 0
(2110 4510);
DISPLAY 0.617021 (2110 4510);
PAINT ORANGE (2110 4510);
FORCEPROP 2 LASTPIN (2100 4450) $PN 99
J 0
(2110 4460);
DISPLAY 0.617021 (2110 4460);
PAINT ORANGE (2110 4460);
FORCEPROP 2 LASTPIN (2100 4350) $PN 40
J 0
(2110 4360);
DISPLAY 0.617021 (2110 4360);
PAINT ORANGE (2110 4360);
FORCEPROP 2 LASTPIN (2100 4250) $PN 29
J 0
(2110 4260);
DISPLAY 0.617021 (2110 4260);
PAINT ORANGE (2110 4260);
FORCEPROP 2 LASTPIN (2100 4200) $PN 30
J 0
(2110 4210);
DISPLAY 0.617021 (2110 4210);
PAINT ORANGE (2110 4210);
FORCEPROP 2 LASTPIN (2100 4150) $PN 18
J 0
(2110 4160);
DISPLAY 0.617021 (2110 4160);
PAINT ORANGE (2110 4160);
FORCEPROP 2 LASTPIN (2100 4100) $PN 19
J 0
(2110 4110);
DISPLAY 0.617021 (2110 4110);
PAINT ORANGE (2110 4110);
FORCEPROP 2 LASTPIN (2100 4050) $PN 7
J 0
(2110 4060);
DISPLAY 0.617021 (2110 4060);
PAINT ORANGE (2110 4060);
FORCEPROP 2 LASTPIN (2100 4000) $PN 8
J 0
(2110 4010);
DISPLAY 0.617021 (2110 4010);
PAINT ORANGE (2110 4010);
FORCEPROP 2 LASTPIN (2100 3950) $PN 197
J 0
(2110 3960);
DISPLAY 0.617021 (2110 3960);
PAINT ORANGE (2110 3960);
FORCEPROP 2 LASTPIN (2100 3900) $PN 196
J 0
(2110 3910);
DISPLAY 0.617021 (2110 3910);
PAINT ORANGE (2110 3910);
FORCEPROP 2 LASTPIN (2100 3850) $PN 278
J 0
(2110 3860);
DISPLAY 0.617021 (2110 3860);
PAINT ORANGE (2110 3860);
FORCEPROP 2 LASTPIN (2100 3800) $PN 277
J 0
(2110 3810);
DISPLAY 0.617021 (2110 3810);
PAINT ORANGE (2110 3810);
FORCEPROP 2 LASTPIN (2100 3750) $PN 267
J 0
(2110 3760);
DISPLAY 0.617021 (2110 3760);
PAINT ORANGE (2110 3760);
FORCEPROP 2 LASTPIN (2100 3700) $PN 266
J 0
(2110 3710);
DISPLAY 0.617021 (2110 3710);
PAINT ORANGE (2110 3710);
FORCEPROP 2 LASTPIN (2100 3650) $PN 256
J 0
(2110 3660);
DISPLAY 0.617021 (2110 3660);
PAINT ORANGE (2110 3660);
FORCEPROP 2 LASTPIN (2100 3600) $PN 255
J 0
(2110 3610);
DISPLAY 0.617021 (2110 3610);
PAINT ORANGE (2110 3610);
FORCEPROP 2 LASTPIN (2100 3550) $PN 245
J 0
(2110 3560);
DISPLAY 0.617021 (2110 3560);
PAINT ORANGE (2110 3560);
FORCEPROP 2 LASTPIN (2100 3450) $PN 186
J 0
(2110 3460);
DISPLAY 0.617021 (2110 3460);
PAINT ORANGE (2110 3460);
FORCEPROP 2 LASTPIN (2100 3400) $PN 185
J 0
(2110 3410);
DISPLAY 0.617021 (2110 3410);
PAINT ORANGE (2110 3410);
FORCEPROP 2 LASTPIN (2100 3350) $PN 175
J 0
(2110 3360);
DISPLAY 0.617021 (2110 3360);
PAINT ORANGE (2110 3360);
FORCEPROP 2 LASTPIN (2100 3300) $PN 174
J 0
(2110 3310);
DISPLAY 0.617021 (2110 3310);
PAINT ORANGE (2110 3310);
FORCEPROP 2 LASTPIN (2100 3250) $PN 164
J 0
(2110 3260);
DISPLAY 0.617021 (2110 3260);
PAINT ORANGE (2110 3260);
FORCEPROP 2 LASTPIN (2100 3200) $PN 163
J 0
(2110 3210);
DISPLAY 0.617021 (2110 3210);
PAINT ORANGE (2110 3210);
FORCEPROP 2 LASTPIN (2100 3150) $PN 153
J 0
(2110 3160);
DISPLAY 0.617021 (2110 3160);
PAINT ORANGE (2110 3160);
FORCEPROP 2 LASTPIN (2100 3100) $PN 152
J 0
(2110 3110);
DISPLAY 0.617021 (2110 3110);
PAINT ORANGE (2110 3110);
FORCEPROP 2 LASTPIN (2100 3500) $PN 244
J 0
(2110 3510);
DISPLAY 0.617021 (2110 3510);
PAINT ORANGE (2110 3510);
FORCEPROP 2 LASTPIN (2100 4300) $PN 41
J 0
(2110 4310);
DISPLAY 0.617021 (2110 4310);
PAINT ORANGE (2110 4310);
FORCEPROP 2 LASTPIN (2100 4400) $PN 100
J 0
(2110 4410);
DISPLAY 0.617021 (2110 4410);
PAINT ORANGE (2110 4410);
FORCEPROP 0 LAST BOM_SS NOPOP
J 0
(1490 5081);
DISPLAY 1.021277 (1490 5081);
PAINT BROWN (1490 5081);
DISPLAY BOTH (1490 5081);
FORCEPROP 2 LASTPIN (2100 4750) $PN 132
J 0
(2110 4760);
DISPLAY 0.617021 (2110 4760);
PAINT ORANGE (2110 4760);
FORCEPROP 1 LAST PACK_TYPE PIP
J 0
(1250 5150);
PAINT SKYBLUE (1250 5150);
DISPLAY INVISIBLE (1250 5150);
FORCEPROP 2 LAST BOM_COST MEM
J 0
(1650 4000);
PAINT ORANGE (1650 4000);
DISPLAY INVISIBLE (1650 4000);
FORCEPROP 2 LAST CDS_LIB mstr_sconn
J 0
(1650 4000);
PAINT ORANGE (1650 4000);
DISPLAY INVISIBLE (1650 4000);
FORCEPROP 2 LAST SEC_TYPE PIP
J 0
(1250 5150);
DISPLAY 1.021277 (1250 5150);
PAINT ORANGE (1250 5150);
DISPLAY INVISIBLE (1250 5150);
FORCEPROP 2 LAST SEC 2
J 0
(1250 5150);
DISPLAY 0.680851 (1250 5150);
PAINT MONO (1250 5150);
DISPLAY INVISIBLE (1250 5150);
FORCEPROP 2 LAST CDS_LOCATION J6T1
J 0
(1250 5100);
DISPLAY 0.617021 (1250 5100);
PAINT AQUA (1250 5100);
DISPLAY INVISIBLE (1250 5100);
FORCEPROP 1 LAST PATH I120
J 0
(1650 5050);
PAINT GREEN (1650 5050);
DISPLAY INVISIBLE (1650 5050);
FORCEPROP 2 LAST ROOM DDR4_CH_A
J 0
(1650 4000);
PAINT ORANGE (1650 4000);
DISPLAY INVISIBLE (1650 4000);
FORCEADD OFFPAGE..1
(-2100 4400);
FORCEPROP 2 LAST $XR1 43 
J 0
(-2411 4400);
DISPLAY 0.638298 (-2411 4400);
PAINT MONO (-2411 4400);
FORCEPROP 2 LAST $XR0 23 
J 0
(-2321 4400);
DISPLAY 0.638298 (-2321 4400);
PAINT MONO (-2321 4400);
FORCEPROP 2 LAST CDS_LIB mstr_standard
J 0
(-2100 4400);
DISPLAY 0.787234 (-2100 4400);
PAINT MONO (-2100 4400);
DISPLAY INVISIBLE (-2100 4400);
FORCEPROP 1 LAST OFFPAGE TRUE
J 0
(-1775 4275);
DISPLAY 0.936170 (-1775 4275);
PAINT GREEN (-1775 4275);
DISPLAY INVISIBLE (-1775 4275);
FORCEPROP 1 LAST COMMENT_BODY TRUE
J 0
(-1975 4300);
DISPLAY 0.936170 (-1975 4300);
PAINT GREEN (-1975 4300);
DISPLAY INVISIBLE (-1975 4300);
FORCEPROP 2 LAST PATH I121
J 0
(-2300 4450);
DISPLAY 1.021277 (-2300 4450);
PAINT ORANGE (-2300 4450);
DISPLAY INVISIBLE (-2300 4450);
FORCEADD TAP..6
(-1450 4150);
FORCEPROP 3 LASTPIN (-1400 4150) SIG_NAME M_A_MA<13>
J 0
(-1390 4160);
DISPLAY 0.659574 (-1390 4160);
PAINT MONO (-1390 4160);
DISPLAY INVISIBLE (-1390 4160);
FORCEPROP 1 LASTPIN (-1400 4150) BN 13
J 0
(-1450 4160);
DISPLAY 0.617021 (-1450 4160);
PAINT PINK (-1450 4160);
FORCEPROP 2 LAST CDS_LIB mstr_standard
J 2
(-1450 4150);
DISPLAY 0.787234 (-1450 4150);
PAINT MONO (-1450 4150);
DISPLAY INVISIBLE (-1450 4150);
FORCEPROP 1 LAST BODY_TYPE PLUMBING
J 0
(-1450 4100);
DISPLAY 1.234043 (-1450 4100);
PAINT GREEN (-1450 4100);
DISPLAY INVISIBLE (-1450 4100);
FORCEPROP 1 LAST HDL_TAP TRUE
J 0
(-1125 4025);
DISPLAY 1.234043 (-1125 4025);
PAINT GREEN (-1125 4025);
DISPLAY INVISIBLE (-1125 4025);
FORCEPROP 1 LAST PATH I122
J 0
(-1452 4150);
DISPLAY 0.872340 (-1452 4150);
PAINT GREEN (-1452 4150);
DISPLAY INVISIBLE (-1452 4150);
FORCEADD TAP..6
(-1450 4050);
FORCEPROP 3 LASTPIN (-1400 4050) SIG_NAME M_A_MA<11>
J 0
(-1390 4060);
DISPLAY 0.659574 (-1390 4060);
PAINT MONO (-1390 4060);
DISPLAY INVISIBLE (-1390 4060);
FORCEPROP 1 LASTPIN (-1400 4050) BN 11
J 0
(-1450 4060);
DISPLAY 0.617021 (-1450 4060);
PAINT PINK (-1450 4060);
FORCEPROP 2 LAST CDS_LIB mstr_standard
J 2
(-1450 4050);
DISPLAY 0.787234 (-1450 4050);
PAINT MONO (-1450 4050);
DISPLAY INVISIBLE (-1450 4050);
FORCEPROP 1 LAST BODY_TYPE PLUMBING
J 0
(-1450 4000);
DISPLAY 1.234043 (-1450 4000);
PAINT GREEN (-1450 4000);
DISPLAY INVISIBLE (-1450 4000);
FORCEPROP 1 LAST HDL_TAP TRUE
J 0
(-1125 3925);
DISPLAY 1.234043 (-1125 3925);
PAINT GREEN (-1125 3925);
DISPLAY INVISIBLE (-1125 3925);
FORCEPROP 1 LAST PATH I123
J 0
(-1452 4050);
DISPLAY 0.872340 (-1452 4050);
PAINT GREEN (-1452 4050);
DISPLAY INVISIBLE (-1452 4050);
FORCEADD TAP..6
(-1450 4100);
FORCEPROP 3 LASTPIN (-1400 4100) SIG_NAME M_A_MA<12>
J 0
(-1390 4110);
DISPLAY 0.659574 (-1390 4110);
PAINT MONO (-1390 4110);
DISPLAY INVISIBLE (-1390 4110);
FORCEPROP 1 LASTPIN (-1400 4100) BN 12
J 0
(-1450 4110);
DISPLAY 0.617021 (-1450 4110);
PAINT PINK (-1450 4110);
FORCEPROP 2 LAST CDS_LIB mstr_standard
J 2
(-1450 4100);
DISPLAY 0.787234 (-1450 4100);
PAINT MONO (-1450 4100);
DISPLAY INVISIBLE (-1450 4100);
FORCEPROP 1 LAST BODY_TYPE PLUMBING
J 0
(-1450 4050);
DISPLAY 1.234043 (-1450 4050);
PAINT GREEN (-1450 4050);
DISPLAY INVISIBLE (-1450 4050);
FORCEPROP 1 LAST HDL_TAP TRUE
J 0
(-1125 3975);
DISPLAY 1.234043 (-1125 3975);
PAINT GREEN (-1125 3975);
DISPLAY INVISIBLE (-1125 3975);
FORCEPROP 1 LAST PATH I124
J 0
(-1452 4100);
DISPLAY 0.872340 (-1452 4100);
PAINT GREEN (-1452 4100);
DISPLAY INVISIBLE (-1452 4100);
FORCEADD TAP..6
(-1450 4200);
FORCEPROP 3 LASTPIN (-1400 4200) SIG_NAME M_A_MA<14>
J 0
(-1390 4210);
DISPLAY 0.659574 (-1390 4210);
PAINT MONO (-1390 4210);
DISPLAY INVISIBLE (-1390 4210);
FORCEPROP 1 LASTPIN (-1400 4200) BN 14
J 0
(-1450 4210);
DISPLAY 0.617021 (-1450 4210);
PAINT PINK (-1450 4210);
FORCEPROP 2 LAST CDS_LIB mstr_standard
J 2
(-1450 4200);
DISPLAY 0.787234 (-1450 4200);
PAINT MONO (-1450 4200);
DISPLAY INVISIBLE (-1450 4200);
FORCEPROP 1 LAST BODY_TYPE PLUMBING
J 0
(-1450 4150);
DISPLAY 1.234043 (-1450 4150);
PAINT GREEN (-1450 4150);
DISPLAY INVISIBLE (-1450 4150);
FORCEPROP 1 LAST HDL_TAP TRUE
J 0
(-1125 4075);
DISPLAY 1.234043 (-1125 4075);
PAINT GREEN (-1125 4075);
DISPLAY INVISIBLE (-1125 4075);
FORCEPROP 1 LAST PATH I125
J 0
(-1452 4200);
DISPLAY 0.872340 (-1452 4200);
PAINT GREEN (-1452 4200);
DISPLAY INVISIBLE (-1452 4200);
FORCEADD TAP..6
(-1450 4250);
FORCEPROP 3 LASTPIN (-1400 4250) SIG_NAME M_A_MA<15>
J 0
(-1390 4260);
DISPLAY 0.659574 (-1390 4260);
PAINT MONO (-1390 4260);
DISPLAY INVISIBLE (-1390 4260);
FORCEPROP 1 LASTPIN (-1400 4250) BN 15
J 0
(-1450 4260);
DISPLAY 0.617021 (-1450 4260);
PAINT PINK (-1450 4260);
FORCEPROP 2 LAST CDS_LIB mstr_standard
J 2
(-1450 4250);
DISPLAY 0.787234 (-1450 4250);
PAINT MONO (-1450 4250);
DISPLAY INVISIBLE (-1450 4250);
FORCEPROP 1 LAST BODY_TYPE PLUMBING
J 0
(-1450 4200);
DISPLAY 1.234043 (-1450 4200);
PAINT GREEN (-1450 4200);
DISPLAY INVISIBLE (-1450 4200);
FORCEPROP 1 LAST HDL_TAP TRUE
J 0
(-1125 4125);
DISPLAY 1.234043 (-1125 4125);
PAINT GREEN (-1125 4125);
DISPLAY INVISIBLE (-1125 4125);
FORCEPROP 1 LAST PATH I126
J 0
(-1452 4250);
DISPLAY 0.872340 (-1452 4250);
PAINT GREEN (-1452 4250);
DISPLAY INVISIBLE (-1452 4250);
FORCEADD TAP..6
(-1450 4300);
FORCEPROP 3 LASTPIN (-1400 4300) SIG_NAME M_A_MA<16>
J 0
(-1390 4310);
DISPLAY 0.659574 (-1390 4310);
PAINT MONO (-1390 4310);
DISPLAY INVISIBLE (-1390 4310);
FORCEPROP 1 LASTPIN (-1400 4300) BN 16
J 0
(-1450 4310);
DISPLAY 0.617021 (-1450 4310);
PAINT PINK (-1450 4310);
FORCEPROP 2 LAST CDS_LIB mstr_standard
J 2
(-1450 4300);
DISPLAY 0.787234 (-1450 4300);
PAINT MONO (-1450 4300);
DISPLAY INVISIBLE (-1450 4300);
FORCEPROP 1 LAST BODY_TYPE PLUMBING
J 0
(-1450 4250);
DISPLAY 1.234043 (-1450 4250);
PAINT GREEN (-1450 4250);
DISPLAY INVISIBLE (-1450 4250);
FORCEPROP 1 LAST HDL_TAP TRUE
J 0
(-1125 4175);
DISPLAY 1.234043 (-1125 4175);
PAINT GREEN (-1125 4175);
DISPLAY INVISIBLE (-1125 4175);
FORCEPROP 1 LAST PATH I127
J 0
(-1452 4300);
DISPLAY 0.872340 (-1452 4300);
PAINT GREEN (-1452 4300);
DISPLAY INVISIBLE (-1452 4300);
FORCEADD TAP..6
(-1450 4350);
FORCEPROP 3 LASTPIN (-1400 4350) SIG_NAME M_A_MA<17>
J 0
(-1390 4360);
DISPLAY 0.659574 (-1390 4360);
PAINT MONO (-1390 4360);
DISPLAY INVISIBLE (-1390 4360);
FORCEPROP 1 LASTPIN (-1400 4350) BN 17
J 0
(-1450 4360);
DISPLAY 0.617021 (-1450 4360);
PAINT PINK (-1450 4360);
FORCEPROP 2 LAST CDS_LIB mstr_standard
J 0
(-1450 4350);
DISPLAY 0.787234 (-1450 4350);
PAINT MONO (-1450 4350);
DISPLAY INVISIBLE (-1450 4350);
FORCEPROP 1 LAST BODY_TYPE PLUMBING
J 0
(-1450 4300);
DISPLAY 1.234043 (-1450 4300);
PAINT GREEN (-1450 4300);
DISPLAY INVISIBLE (-1450 4300);
FORCEPROP 1 LAST HDL_TAP TRUE
J 0
(-1125 4225);
DISPLAY 1.234043 (-1125 4225);
PAINT GREEN (-1125 4225);
DISPLAY INVISIBLE (-1125 4225);
FORCEPROP 1 LAST PATH I128
J 0
(-1452 4350);
DISPLAY 0.872340 (-1452 4350);
PAINT GREEN (-1452 4350);
DISPLAY INVISIBLE (-1452 4350);
FORCEADD TAP..6
R 2
(100 4050);
FORCEPROP 3 LASTPIN (50 4050) SIG_NAME M_A_DQ<57>
J 0
(60 4060);
DISPLAY 0.659574 (60 4060);
PAINT MONO (60 4060);
DISPLAY INVISIBLE (60 4060);
FORCEPROP 1 LASTPIN (50 4050) BN 57
J 2
(100 4060);
DISPLAY 0.617021 (100 4060);
PAINT PINK (100 4060);
FORCEPROP 2 LAST CDS_LIB mstr_standard
J 2
(100 4050);
DISPLAY 0.787234 (100 4050);
PAINT MONO (100 4050);
DISPLAY INVISIBLE (100 4050);
FORCEPROP 1 LAST BODY_TYPE PLUMBING
J 2
(100 4000);
DISPLAY 1.234043 (100 4000);
PAINT GREEN (100 4000);
DISPLAY INVISIBLE (100 4000);
FORCEPROP 1 LAST HDL_TAP TRUE
J 2
(-225 3925);
DISPLAY 1.234043 (-225 3925);
PAINT GREEN (-225 3925);
DISPLAY INVISIBLE (-225 3925);
FORCEPROP 1 LAST PATH I129
J 2
(102 4050);
DISPLAY 0.872340 (102 4050);
PAINT GREEN (102 4050);
DISPLAY INVISIBLE (102 4050);
FORCEADD SCONN288_H44441003..1
(-700 2700);
FORCEPROP 1 LAST LOCATION J6T1
J 0
(-1150 4600);
DISPLAY 0.617021 (-1150 4600);
PAINT AQUA (-1150 4600);
FORCEPROP 1 LAST PART_NUMBER H44441-003
J 0
(-1150 700);
DISPLAY 0.617021 (-1150 700);
PAINT BLUE (-1150 700);
FORCEPROP 2 LASTPIN (-1200 1200) $PN 146
J 2
(-1210 1210);
DISPLAY 0.617021 (-1210 1210);
PAINT ORANGE (-1210 1210);
FORCEPROP 2 LASTPIN (-1200 1550) $PN 284
J 2
(-1210 1560);
DISPLAY 0.617021 (-1210 1560);
PAINT ORANGE (-1210 1560);
FORCEPROP 2 LASTPIN (-1200 1350) $PN 285
J 2
(-1210 1360);
DISPLAY 0.617021 (-1210 1360);
PAINT ORANGE (-1210 1360);
FORCEPROP 2 LASTPIN (-1200 1300) $PN 141
J 2
(-1210 1310);
DISPLAY 0.617021 (-1210 1310);
PAINT ORANGE (-1210 1310);
FORCEPROP 2 LASTPIN (-1200 900) $PN 230
J 2
(-1210 910);
DISPLAY 0.617021 (-1210 910);
PAINT ORANGE (-1210 910);
FORCEPROP 2 LASTPIN (-1200 1500) $PN 238
J 2
(-1210 1510);
DISPLAY 0.617021 (-1210 1510);
PAINT ORANGE (-1210 1510);
FORCEPROP 2 LASTPIN (-1200 1450) $PN 140
J 2
(-1210 1460);
DISPLAY 0.617021 (-1210 1460);
PAINT ORANGE (-1210 1460);
FORCEPROP 2 LASTPIN (-1200 1400) $PN 139
J 2
(-1210 1410);
DISPLAY 0.617021 (-1210 1410);
PAINT ORANGE (-1210 1410);
FORCEPROP 2 LASTPIN (-1200 2850) $PN 237
J 2
(-1210 2860);
DISPLAY 0.617021 (-1210 2860);
PAINT ORANGE (-1210 2860);
FORCEPROP 2 LASTPIN (-1200 2800) $PN 93
J 2
(-1210 2810);
DISPLAY 0.617021 (-1210 2810);
PAINT ORANGE (-1210 2810);
FORCEPROP 2 LASTPIN (-1200 2750) $PN 89
J 2
(-1210 2760);
DISPLAY 0.617021 (-1210 2760);
PAINT ORANGE (-1210 2760);
FORCEPROP 2 LASTPIN (-1200 2700) $PN 84
J 2
(-1210 2710);
DISPLAY 0.617021 (-1210 2710);
PAINT ORANGE (-1210 2710);
FORCEPROP 2 LASTPIN (-1200 1100) $PN 144
J 2
(-1210 1110);
DISPLAY 0.617021 (-1210 1110);
PAINT ORANGE (-1210 1110);
FORCEPROP 2 LASTPIN (-1200 1050) $PN 227
J 2
(-1210 1060);
DISPLAY 0.617021 (-1210 1060);
PAINT ORANGE (-1210 1060);
FORCEPROP 2 LASTPIN (-1200 1000) $PN 205
J 2
(-1210 1010);
DISPLAY 0.617021 (-1210 1010);
PAINT ORANGE (-1210 1010);
FORCEPROP 2 LASTPIN (-1200 1800) $PN 58
J 2
(-1210 1810);
DISPLAY 0.617021 (-1210 1810);
PAINT ORANGE (-1210 1810);
FORCEPROP 2 LASTPIN (-1200 1850) $PN 222
J 2
(-1210 1860);
DISPLAY 0.617021 (-1210 1860);
PAINT ORANGE (-1210 1860);
FORCEPROP 2 LASTPIN (-1200 2450) $PN 91
J 2
(-1210 2460);
DISPLAY 0.617021 (-1210 2460);
PAINT ORANGE (-1210 2460);
FORCEPROP 2 LASTPIN (-1200 2400) $PN 87
J 2
(-1210 2410);
DISPLAY 0.617021 (-1210 2410);
PAINT ORANGE (-1210 2410);
FORCEPROP 2 LASTPIN (-1200 1750) $PN 78
J 2
(-1210 1760);
DISPLAY 0.617021 (-1210 1760);
PAINT ORANGE (-1210 1760);
FORCEPROP 2 LASTPIN (-200 4150) $PN 282
J 0
(-190 4160);
DISPLAY 0.617021 (-190 4160);
PAINT ORANGE (-190 4160);
FORCEPROP 2 LASTPIN (-200 4050) $PN 275
J 0
(-190 4060);
DISPLAY 0.617021 (-190 4060);
PAINT ORANGE (-190 4060);
FORCEPROP 2 LASTPIN (-200 3950) $PN 269
J 0
(-190 3960);
DISPLAY 0.617021 (-190 3960);
PAINT ORANGE (-190 3960);
FORCEPROP 2 LASTPIN (-200 3900) $PN 124
J 0
(-190 3910);
DISPLAY 0.617021 (-190 3910);
PAINT ORANGE (-190 3910);
FORCEPROP 2 LASTPIN (-200 3850) $PN 262
J 0
(-190 3860);
DISPLAY 0.617021 (-190 3860);
PAINT ORANGE (-190 3860);
FORCEPROP 2 LASTPIN (-200 3800) $PN 117
J 0
(-190 3810);
DISPLAY 0.617021 (-190 3810);
PAINT ORANGE (-190 3810);
FORCEPROP 2 LASTPIN (-200 3750) $PN 271
J 0
(-190 3760);
DISPLAY 0.617021 (-190 3760);
PAINT ORANGE (-190 3760);
FORCEPROP 2 LASTPIN (-200 3650) $PN 264
J 0
(-190 3660);
DISPLAY 0.617021 (-190 3660);
PAINT ORANGE (-190 3660);
FORCEPROP 2 LASTPIN (-200 3600) $PN 119
J 0
(-190 3610);
DISPLAY 0.617021 (-190 3610);
PAINT ORANGE (-190 3610);
FORCEPROP 2 LASTPIN (-200 3550) $PN 258
J 0
(-190 3560);
DISPLAY 0.617021 (-190 3560);
PAINT ORANGE (-190 3560);
FORCEPROP 2 LASTPIN (-200 3500) $PN 113
J 0
(-190 3510);
DISPLAY 0.617021 (-190 3510);
PAINT ORANGE (-190 3510);
FORCEPROP 2 LASTPIN (-200 3450) $PN 251
J 0
(-190 3460);
DISPLAY 0.617021 (-190 3460);
PAINT ORANGE (-190 3460);
FORCEPROP 2 LASTPIN (-200 3400) $PN 106
J 0
(-190 3410);
DISPLAY 0.617021 (-190 3410);
PAINT ORANGE (-190 3410);
FORCEPROP 2 LASTPIN (-200 3350) $PN 260
J 0
(-190 3360);
DISPLAY 0.617021 (-190 3360);
PAINT ORANGE (-190 3360);
FORCEPROP 2 LASTPIN (-200 3300) $PN 115
J 0
(-190 3310);
DISPLAY 0.617021 (-190 3310);
PAINT ORANGE (-190 3310);
FORCEPROP 2 LASTPIN (-200 3250) $PN 253
J 0
(-190 3260);
DISPLAY 0.617021 (-190 3260);
PAINT ORANGE (-190 3260);
FORCEPROP 2 LASTPIN (-200 3200) $PN 108
J 0
(-190 3210);
DISPLAY 0.617021 (-190 3210);
PAINT ORANGE (-190 3210);
FORCEPROP 2 LASTPIN (-200 3150) $PN 247
J 0
(-190 3160);
DISPLAY 0.617021 (-190 3160);
PAINT ORANGE (-190 3160);
FORCEPROP 2 LASTPIN (-200 3100) $PN 102
J 0
(-190 3110);
DISPLAY 0.617021 (-190 3110);
PAINT ORANGE (-190 3110);
FORCEPROP 2 LASTPIN (-200 3050) $PN 240
J 0
(-190 3060);
DISPLAY 0.617021 (-190 3060);
PAINT ORANGE (-190 3060);
FORCEPROP 2 LASTPIN (-200 3000) $PN 95
J 0
(-190 3010);
DISPLAY 0.617021 (-190 3010);
PAINT ORANGE (-190 3010);
FORCEPROP 2 LASTPIN (-200 2950) $PN 249
J 0
(-190 2960);
DISPLAY 0.617021 (-190 2960);
PAINT ORANGE (-190 2960);
FORCEPROP 2 LASTPIN (-200 2900) $PN 104
J 0
(-190 2910);
DISPLAY 0.617021 (-190 2910);
PAINT ORANGE (-190 2910);
FORCEPROP 2 LASTPIN (-200 2850) $PN 242
J 0
(-190 2860);
DISPLAY 0.617021 (-190 2860);
PAINT ORANGE (-190 2860);
FORCEPROP 2 LASTPIN (-200 2800) $PN 97
J 0
(-190 2810);
DISPLAY 0.617021 (-190 2810);
PAINT ORANGE (-190 2810);
FORCEPROP 2 LASTPIN (-200 2750) $PN 188
J 0
(-190 2760);
DISPLAY 0.617021 (-190 2760);
PAINT ORANGE (-190 2760);
FORCEPROP 2 LASTPIN (-200 2700) $PN 43
J 0
(-190 2710);
DISPLAY 0.617021 (-190 2710);
PAINT ORANGE (-190 2710);
FORCEPROP 2 LASTPIN (-200 2650) $PN 181
J 0
(-190 2660);
DISPLAY 0.617021 (-190 2660);
PAINT ORANGE (-190 2660);
FORCEPROP 2 LASTPIN (-200 2500) $PN 45
J 0
(-190 2510);
DISPLAY 0.617021 (-190 2510);
PAINT ORANGE (-190 2510);
FORCEPROP 2 LASTPIN (-200 2450) $PN 183
J 0
(-190 2460);
DISPLAY 0.617021 (-190 2460);
PAINT ORANGE (-190 2460);
FORCEPROP 2 LASTPIN (-200 2400) $PN 38
J 0
(-190 2410);
DISPLAY 0.617021 (-190 2410);
PAINT ORANGE (-190 2410);
FORCEPROP 2 LASTPIN (-200 2350) $PN 177
J 0
(-190 2360);
DISPLAY 0.617021 (-190 2360);
PAINT ORANGE (-190 2360);
FORCEPROP 2 LASTPIN (-200 2300) $PN 32
J 0
(-190 2310);
DISPLAY 0.617021 (-190 2310);
PAINT ORANGE (-190 2310);
FORCEPROP 2 LASTPIN (-200 2250) $PN 170
J 0
(-190 2260);
DISPLAY 0.617021 (-190 2260);
PAINT ORANGE (-190 2260);
FORCEPROP 2 LASTPIN (-200 2200) $PN 25
J 0
(-190 2210);
DISPLAY 0.617021 (-190 2210);
PAINT ORANGE (-190 2210);
FORCEPROP 2 LASTPIN (-200 2150) $PN 179
J 0
(-190 2160);
DISPLAY 0.617021 (-190 2160);
PAINT ORANGE (-190 2160);
FORCEPROP 2 LASTPIN (-200 2100) $PN 34
J 0
(-190 2110);
DISPLAY 0.617021 (-190 2110);
PAINT ORANGE (-190 2110);
FORCEPROP 2 LASTPIN (-200 1900) $PN 21
J 0
(-190 1910);
DISPLAY 0.617021 (-190 1910);
PAINT ORANGE (-190 1910);
FORCEPROP 2 LASTPIN (-200 1800) $PN 14
J 0
(-190 1810);
DISPLAY 0.617021 (-190 1810);
PAINT ORANGE (-190 1810);
FORCEPROP 2 LASTPIN (-200 1750) $PN 168
J 0
(-190 1760);
DISPLAY 0.617021 (-190 1760);
PAINT ORANGE (-190 1760);
FORCEPROP 2 LASTPIN (-200 1700) $PN 23
J 0
(-190 1710);
DISPLAY 0.617021 (-190 1710);
PAINT ORANGE (-190 1710);
FORCEPROP 2 LASTPIN (-200 1650) $PN 161
J 0
(-190 1660);
DISPLAY 0.617021 (-190 1660);
PAINT ORANGE (-190 1660);
FORCEPROP 2 LASTPIN (-200 1600) $PN 16
J 0
(-190 1610);
DISPLAY 0.617021 (-190 1610);
PAINT ORANGE (-190 1610);
FORCEPROP 2 LASTPIN (-200 1550) $PN 155
J 0
(-190 1560);
DISPLAY 0.617021 (-190 1560);
PAINT ORANGE (-190 1560);
FORCEPROP 2 LASTPIN (-200 1500) $PN 10
J 0
(-190 1510);
DISPLAY 0.617021 (-190 1510);
PAINT ORANGE (-190 1510);
FORCEPROP 2 LASTPIN (-200 1450) $PN 148
J 0
(-190 1460);
DISPLAY 0.617021 (-190 1460);
PAINT ORANGE (-190 1460);
FORCEPROP 2 LASTPIN (-200 1400) $PN 3
J 0
(-190 1410);
DISPLAY 0.617021 (-190 1410);
PAINT ORANGE (-190 1410);
FORCEPROP 2 LASTPIN (-200 1350) $PN 157
J 0
(-190 1360);
DISPLAY 0.617021 (-190 1360);
PAINT ORANGE (-190 1360);
FORCEPROP 2 LASTPIN (-200 1300) $PN 12
J 0
(-190 1310);
DISPLAY 0.617021 (-190 1310);
PAINT ORANGE (-190 1310);
FORCEPROP 2 LASTPIN (-200 1250) $PN 150
J 0
(-190 1260);
DISPLAY 0.617021 (-190 1260);
PAINT ORANGE (-190 1260);
FORCEPROP 2 LASTPIN (-200 1200) $PN 5
J 0
(-190 1210);
DISPLAY 0.617021 (-190 1210);
PAINT ORANGE (-190 1210);
FORCEPROP 2 LASTPIN (-1200 2600) $PN 203
J 2
(-1210 2610);
DISPLAY 0.617021 (-1210 2610);
PAINT ORANGE (-1210 2610);
FORCEPROP 2 LASTPIN (-1200 2550) $PN 60
J 2
(-1210 2560);
DISPLAY 0.617021 (-1210 2560);
PAINT ORANGE (-1210 2560);
FORCEPROP 2 LASTPIN (-1200 3150) $PN 218
J 2
(-1210 3160);
DISPLAY 0.617021 (-1210 3160);
PAINT ORANGE (-1210 3160);
FORCEPROP 2 LASTPIN (-1200 3100) $PN 219
J 2
(-1210 3110);
DISPLAY 0.617021 (-1210 3110);
PAINT ORANGE (-1210 3110);
FORCEPROP 2 LASTPIN (-1200 3050) $PN 74
J 2
(-1210 3060);
DISPLAY 0.617021 (-1210 3060);
PAINT ORANGE (-1210 3060);
FORCEPROP 2 LASTPIN (-1200 3000) $PN 75
J 2
(-1210 3010);
DISPLAY 0.617021 (-1210 3010);
PAINT ORANGE (-1210 3010);
FORCEPROP 2 LASTPIN (-1200 2300) $PN 199
J 2
(-1210 2310);
DISPLAY 0.617021 (-1210 2310);
PAINT ORANGE (-1210 2310);
FORCEPROP 2 LASTPIN (-1200 2250) $PN 54
J 2
(-1210 2260);
DISPLAY 0.617021 (-1210 2260);
PAINT ORANGE (-1210 2260);
FORCEPROP 2 LASTPIN (-1200 2200) $PN 192
J 2
(-1210 2210);
DISPLAY 0.617021 (-1210 2210);
PAINT ORANGE (-1210 2210);
FORCEPROP 2 LASTPIN (-1200 2150) $PN 47
J 2
(-1210 2160);
DISPLAY 0.617021 (-1210 2160);
PAINT ORANGE (-1210 2160);
FORCEPROP 2 LASTPIN (-1200 2100) $PN 201
J 2
(-1210 2110);
DISPLAY 0.617021 (-1210 2110);
PAINT ORANGE (-1210 2110);
FORCEPROP 2 LASTPIN (-1200 2050) $PN 56
J 2
(-1210 2060);
DISPLAY 0.617021 (-1210 2060);
PAINT ORANGE (-1210 2060);
FORCEPROP 2 LASTPIN (-1200 2000) $PN 194
J 2
(-1210 2010);
DISPLAY 0.617021 (-1210 2010);
PAINT ORANGE (-1210 2010);
FORCEPROP 2 LASTPIN (-1200 1950) $PN 49
J 2
(-1210 1960);
DISPLAY 0.617021 (-1210 1960);
PAINT ORANGE (-1210 1960);
FORCEPROP 2 LASTPIN (-1200 2900) $PN 235
J 2
(-1210 2910);
DISPLAY 0.617021 (-1210 2910);
PAINT ORANGE (-1210 2910);
FORCEPROP 2 LASTPIN (-1200 3300) $PN 207
J 2
(-1210 3310);
DISPLAY 0.617021 (-1210 3310);
PAINT ORANGE (-1210 3310);
FORCEPROP 2 LASTPIN (-1200 3250) $PN 63
J 2
(-1210 3260);
DISPLAY 0.617021 (-1210 3260);
PAINT ORANGE (-1210 3260);
FORCEPROP 2 LASTPIN (-1200 3350) $PN 81
J 2
(-1210 3360);
DISPLAY 0.617021 (-1210 3360);
PAINT ORANGE (-1210 3360);
FORCEPROP 2 LASTPIN (-1200 1700) $PN 208
J 2
(-1210 1710);
DISPLAY 0.617021 (-1210 1710);
PAINT ORANGE (-1210 1710);
FORCEPROP 2 LASTPIN (-1200 1650) $PN 62
J 2
(-1210 1660);
DISPLAY 0.617021 (-1210 1660);
PAINT ORANGE (-1210 1660);
FORCEPROP 2 LASTPIN (-1200 4350) $PN 234
J 2
(-1210 4360);
DISPLAY 0.617021 (-1210 4360);
PAINT ORANGE (-1210 4360);
FORCEPROP 2 LASTPIN (-1200 4300) $PN 82
J 2
(-1210 4310);
DISPLAY 0.617021 (-1210 4310);
PAINT ORANGE (-1210 4310);
FORCEPROP 2 LASTPIN (-1200 4250) $PN 86
J 2
(-1210 4260);
DISPLAY 0.617021 (-1210 4260);
PAINT ORANGE (-1210 4260);
FORCEPROP 2 LASTPIN (-1200 4200) $PN 228
J 2
(-1210 4210);
DISPLAY 0.617021 (-1210 4210);
PAINT ORANGE (-1210 4210);
FORCEPROP 2 LASTPIN (-1200 4150) $PN 232
J 2
(-1210 4160);
DISPLAY 0.617021 (-1210 4160);
PAINT ORANGE (-1210 4160);
FORCEPROP 2 LASTPIN (-1200 4100) $PN 65
J 2
(-1210 4110);
DISPLAY 0.617021 (-1210 4110);
PAINT ORANGE (-1210 4110);
FORCEPROP 2 LASTPIN (-1200 4050) $PN 210
J 2
(-1210 4060);
DISPLAY 0.617021 (-1210 4060);
PAINT ORANGE (-1210 4060);
FORCEPROP 2 LASTPIN (-1200 4000) $PN 225
J 2
(-1210 4010);
DISPLAY 0.617021 (-1210 4010);
PAINT ORANGE (-1210 4010);
FORCEPROP 2 LASTPIN (-1200 3950) $PN 66
J 2
(-1210 3960);
DISPLAY 0.617021 (-1210 3960);
PAINT ORANGE (-1210 3960);
FORCEPROP 2 LASTPIN (-1200 3900) $PN 68
J 2
(-1210 3910);
DISPLAY 0.617021 (-1210 3910);
PAINT ORANGE (-1210 3910);
FORCEPROP 2 LASTPIN (-1200 3850) $PN 211
J 2
(-1210 3860);
DISPLAY 0.617021 (-1210 3860);
PAINT ORANGE (-1210 3860);
FORCEPROP 2 LASTPIN (-1200 3800) $PN 69
J 2
(-1210 3810);
DISPLAY 0.617021 (-1210 3810);
PAINT ORANGE (-1210 3810);
FORCEPROP 2 LASTPIN (-1200 3750) $PN 213
J 2
(-1210 3760);
DISPLAY 0.617021 (-1210 3760);
PAINT ORANGE (-1210 3760);
FORCEPROP 2 LASTPIN (-1200 3700) $PN 214
J 2
(-1210 3710);
DISPLAY 0.617021 (-1210 3710);
PAINT ORANGE (-1210 3710);
FORCEPROP 2 LASTPIN (-1200 3650) $PN 71
J 2
(-1210 3660);
DISPLAY 0.617021 (-1210 3660);
PAINT ORANGE (-1210 3660);
FORCEPROP 2 LASTPIN (-1200 3600) $PN 216
J 2
(-1210 3610);
DISPLAY 0.617021 (-1210 3610);
PAINT ORANGE (-1210 3610);
FORCEPROP 2 LASTPIN (-1200 3550) $PN 72
J 2
(-1210 3560);
DISPLAY 0.617021 (-1210 3560);
PAINT ORANGE (-1210 3560);
FORCEPROP 2 LASTPIN (-1200 3500) $PN 79
J 2
(-1210 3510);
DISPLAY 0.617021 (-1210 3510);
PAINT ORANGE (-1210 3510);
FORCEPROP 2 LASTPIN (-200 3700) $PN 126
J 0
(-190 3710);
DISPLAY 0.617021 (-190 3710);
PAINT ORANGE (-190 3710);
FORCEPROP 1 LAST MATERIAL SCONN
J 0
(-1150 4550);
DISPLAY 0.617021 (-1150 4550);
PAINT SKYBLUE (-1150 4550);
FORCEPROP 2 LASTPIN (-1200 3400) $PN 224
J 2
(-1210 3410);
DISPLAY 0.617021 (-1210 3410);
PAINT ORANGE (-1210 3410);
FORCEPROP 2 LASTPIN (-200 4000) $PN 130
J 0
(-190 4010);
DISPLAY 0.617021 (-190 4010);
PAINT ORANGE (-190 4010);
FORCEPROP 2 LASTPIN (-200 4100) $PN 137
J 0
(-190 4110);
DISPLAY 0.617021 (-190 4110);
PAINT ORANGE (-190 4110);
FORCEPROP 2 LASTPIN (-200 4200) $PN 128
J 0
(-190 4210);
DISPLAY 0.617021 (-190 4210);
PAINT ORANGE (-190 4210);
FORCEPROP 2 LASTPIN (-200 4350) $PN 280
J 0
(-190 4360);
DISPLAY 0.617021 (-190 4360);
PAINT ORANGE (-190 4360);
FORCEPROP 2 LASTPIN (-200 4300) $PN 135
J 0
(-190 4310);
DISPLAY 0.617021 (-190 4310);
PAINT ORANGE (-190 4310);
FORCEPROP 2 LASTPIN (-200 1850) $PN 159
J 0
(-190 1860);
DISPLAY 0.617021 (-190 1860);
PAINT ORANGE (-190 1860);
FORCEPROP 2 LASTPIN (-200 1950) $PN 166
J 0
(-190 1960);
DISPLAY 0.617021 (-190 1960);
PAINT ORANGE (-190 1960);
FORCEPROP 2 LASTPIN (-200 2000) $PN 27
J 0
(-190 2010);
DISPLAY 0.617021 (-190 2010);
PAINT ORANGE (-190 2010);
FORCEPROP 2 LASTPIN (-200 2050) $PN 172
J 0
(-190 2060);
DISPLAY 0.617021 (-190 2060);
PAINT ORANGE (-190 2060);
FORCEPROP 2 LASTPIN (-200 2550) $PN 190
J 0
(-190 2560);
DISPLAY 0.617021 (-190 2560);
PAINT ORANGE (-190 2560);
FORCEPROP 2 LASTPIN (-200 2600) $PN 36
J 0
(-190 2610);
DISPLAY 0.617021 (-190 2610);
PAINT ORANGE (-190 2610);
FORCEPROP 2 LASTPIN (-200 4250) $PN 273
J 0
(-190 4260);
DISPLAY 0.617021 (-190 4260);
PAINT ORANGE (-190 4260);
FORCEPROP 0 LAST BOM_SS NOPOP
J 0
(-960 4556);
DISPLAY 1.021277 (-960 4556);
PAINT BROWN (-960 4556);
DISPLAY BOTH (-960 4556);
FORCEPROP 1 LAST PACK_TYPE PIP
J 0
(-1150 4650);
PAINT SKYBLUE (-1150 4650);
DISPLAY INVISIBLE (-1150 4650);
FORCEPROP 2 LAST BOM_COST MEM
J 0
(-700 2700);
PAINT ORANGE (-700 2700);
DISPLAY INVISIBLE (-700 2700);
FORCEPROP 2 LAST CDS_LIB mstr_sconn
J 0
(-700 2700);
PAINT ORANGE (-700 2700);
DISPLAY INVISIBLE (-700 2700);
FORCEPROP 2 LAST SEC_TYPE PIP
J 0
(-1150 4650);
DISPLAY 1.021277 (-1150 4650);
PAINT ORANGE (-1150 4650);
DISPLAY INVISIBLE (-1150 4650);
FORCEPROP 2 LAST SEC 1
J 0
(-1150 4650);
DISPLAY 0.680851 (-1150 4650);
PAINT MONO (-1150 4650);
DISPLAY INVISIBLE (-1150 4650);
FORCEPROP 2 LAST CDS_LOCATION J6T1
J 0
(-1150 4600);
DISPLAY 0.617021 (-1150 4600);
PAINT AQUA (-1150 4600);
DISPLAY INVISIBLE (-1150 4600);
FORCEPROP 1 LAST PATH I13
J 0
(-700 4550);
PAINT GREEN (-700 4550);
DISPLAY INVISIBLE (-700 4550);
FORCEPROP 2 LAST ROOM DDR4_CH_A
J 0
(-700 2700);
PAINT ORANGE (-700 2700);
DISPLAY INVISIBLE (-700 2700);
FORCEADD TAP..6
R 2
(100 4100);
FORCEPROP 3 LASTPIN (50 4100) SIG_NAME M_A_DQ<58>
J 0
(60 4110);
DISPLAY 0.659574 (60 4110);
PAINT MONO (60 4110);
DISPLAY INVISIBLE (60 4110);
FORCEPROP 1 LASTPIN (50 4100) BN 58
J 2
(100 4110);
DISPLAY 0.617021 (100 4110);
PAINT PINK (100 4110);
FORCEPROP 2 LAST CDS_LIB mstr_standard
J 2
(100 4100);
DISPLAY 0.787234 (100 4100);
PAINT MONO (100 4100);
DISPLAY INVISIBLE (100 4100);
FORCEPROP 1 LAST BODY_TYPE PLUMBING
J 2
(100 4050);
DISPLAY 1.234043 (100 4050);
PAINT GREEN (100 4050);
DISPLAY INVISIBLE (100 4050);
FORCEPROP 1 LAST HDL_TAP TRUE
J 2
(-225 3975);
DISPLAY 1.234043 (-225 3975);
PAINT GREEN (-225 3975);
DISPLAY INVISIBLE (-225 3975);
FORCEPROP 1 LAST PATH I130
J 2
(102 4100);
DISPLAY 0.872340 (102 4100);
PAINT GREEN (102 4100);
DISPLAY INVISIBLE (102 4100);
FORCEADD TAP..6
R 2
(100 4150);
FORCEPROP 3 LASTPIN (50 4150) SIG_NAME M_A_DQ<59>
J 0
(60 4160);
DISPLAY 0.659574 (60 4160);
PAINT MONO (60 4160);
DISPLAY INVISIBLE (60 4160);
FORCEPROP 1 LASTPIN (50 4150) BN 59
J 2
(100 4160);
DISPLAY 0.617021 (100 4160);
PAINT PINK (100 4160);
FORCEPROP 2 LAST CDS_LIB mstr_standard
J 2
(100 4150);
DISPLAY 0.787234 (100 4150);
PAINT MONO (100 4150);
DISPLAY INVISIBLE (100 4150);
FORCEPROP 1 LAST BODY_TYPE PLUMBING
J 2
(100 4100);
DISPLAY 1.234043 (100 4100);
PAINT GREEN (100 4100);
DISPLAY INVISIBLE (100 4100);
FORCEPROP 1 LAST HDL_TAP TRUE
J 2
(-225 4025);
DISPLAY 1.234043 (-225 4025);
PAINT GREEN (-225 4025);
DISPLAY INVISIBLE (-225 4025);
FORCEPROP 1 LAST PATH I131
J 2
(102 4150);
DISPLAY 0.872340 (102 4150);
PAINT GREEN (102 4150);
DISPLAY INVISIBLE (102 4150);
FORCEADD TAP..6
R 2
(100 4200);
FORCEPROP 3 LASTPIN (50 4200) SIG_NAME M_A_DQ<60>
J 0
(60 4210);
DISPLAY 0.659574 (60 4210);
PAINT MONO (60 4210);
DISPLAY INVISIBLE (60 4210);
FORCEPROP 1 LASTPIN (50 4200) BN 60
J 2
(100 4210);
DISPLAY 0.617021 (100 4210);
PAINT PINK (100 4210);
FORCEPROP 2 LAST CDS_LIB mstr_standard
J 2
(100 4200);
DISPLAY 0.787234 (100 4200);
PAINT MONO (100 4200);
DISPLAY INVISIBLE (100 4200);
FORCEPROP 1 LAST BODY_TYPE PLUMBING
J 2
(100 4150);
DISPLAY 1.234043 (100 4150);
PAINT GREEN (100 4150);
DISPLAY INVISIBLE (100 4150);
FORCEPROP 1 LAST HDL_TAP TRUE
J 2
(-225 4075);
DISPLAY 1.234043 (-225 4075);
PAINT GREEN (-225 4075);
DISPLAY INVISIBLE (-225 4075);
FORCEPROP 1 LAST PATH I132
J 2
(102 4200);
DISPLAY 0.872340 (102 4200);
PAINT GREEN (102 4200);
DISPLAY INVISIBLE (102 4200);
FORCEADD TAP..6
R 2
(100 4300);
FORCEPROP 3 LASTPIN (50 4300) SIG_NAME M_A_DQ<62>
J 0
(60 4310);
DISPLAY 0.659574 (60 4310);
PAINT MONO (60 4310);
DISPLAY INVISIBLE (60 4310);
FORCEPROP 1 LASTPIN (50 4300) BN 62
J 2
(100 4310);
DISPLAY 0.617021 (100 4310);
PAINT PINK (100 4310);
FORCEPROP 2 LAST CDS_LIB mstr_standard
J 2
(100 4300);
DISPLAY 0.787234 (100 4300);
PAINT MONO (100 4300);
DISPLAY INVISIBLE (100 4300);
FORCEPROP 1 LAST BODY_TYPE PLUMBING
J 2
(100 4250);
DISPLAY 1.234043 (100 4250);
PAINT GREEN (100 4250);
DISPLAY INVISIBLE (100 4250);
FORCEPROP 1 LAST HDL_TAP TRUE
J 2
(-225 4175);
DISPLAY 1.234043 (-225 4175);
PAINT GREEN (-225 4175);
DISPLAY INVISIBLE (-225 4175);
FORCEPROP 1 LAST PATH I133
J 2
(102 4300);
DISPLAY 0.872340 (102 4300);
PAINT GREEN (102 4300);
DISPLAY INVISIBLE (102 4300);
FORCEADD TAP..6
R 2
(100 4250);
FORCEPROP 3 LASTPIN (50 4250) SIG_NAME M_A_DQ<61>
J 0
(60 4260);
DISPLAY 0.659574 (60 4260);
PAINT MONO (60 4260);
DISPLAY INVISIBLE (60 4260);
FORCEPROP 1 LASTPIN (50 4250) BN 61
J 2
(100 4260);
DISPLAY 0.617021 (100 4260);
PAINT PINK (100 4260);
FORCEPROP 2 LAST CDS_LIB mstr_standard
J 2
(100 4250);
DISPLAY 0.787234 (100 4250);
PAINT MONO (100 4250);
DISPLAY INVISIBLE (100 4250);
FORCEPROP 1 LAST BODY_TYPE PLUMBING
J 2
(100 4200);
DISPLAY 1.234043 (100 4200);
PAINT GREEN (100 4200);
DISPLAY INVISIBLE (100 4200);
FORCEPROP 1 LAST HDL_TAP TRUE
J 2
(-225 4125);
DISPLAY 1.234043 (-225 4125);
PAINT GREEN (-225 4125);
DISPLAY INVISIBLE (-225 4125);
FORCEPROP 1 LAST PATH I134
J 2
(102 4250);
DISPLAY 0.872340 (102 4250);
PAINT GREEN (102 4250);
DISPLAY INVISIBLE (102 4250);
FORCEADD TAP..6
R 2
(100 4350);
FORCEPROP 3 LASTPIN (50 4350) SIG_NAME M_A_DQ<63>
J 0
(60 4360);
DISPLAY 0.659574 (60 4360);
PAINT MONO (60 4360);
DISPLAY INVISIBLE (60 4360);
FORCEPROP 1 LASTPIN (50 4350) BN 63
J 2
(100 4360);
DISPLAY 0.617021 (100 4360);
PAINT PINK (100 4360);
FORCEPROP 2 LAST CDS_LIB mstr_standard
J 2
(100 4350);
DISPLAY 0.787234 (100 4350);
PAINT MONO (100 4350);
DISPLAY INVISIBLE (100 4350);
FORCEPROP 1 LAST BODY_TYPE PLUMBING
J 2
(100 4300);
DISPLAY 1.234043 (100 4300);
PAINT GREEN (100 4300);
DISPLAY INVISIBLE (100 4300);
FORCEPROP 1 LAST HDL_TAP TRUE
J 2
(-225 4225);
DISPLAY 1.234043 (-225 4225);
PAINT GREEN (-225 4225);
DISPLAY INVISIBLE (-225 4225);
FORCEPROP 1 LAST PATH I135
J 2
(102 4350);
DISPLAY 0.872340 (102 4350);
PAINT GREEN (102 4350);
DISPLAY INVISIBLE (102 4350);
FORCEADD OFFPAGE..3
(700 4400);
FORCEPROP 2 LAST $XR1 43 
J 0
(1004 4400);
DISPLAY 0.638298 (1004 4400);
PAINT MONO (1004 4400);
FORCEPROP 2 LAST $XR0 23 
J 0
(914 4400);
DISPLAY 0.638298 (914 4400);
PAINT MONO (914 4400);
FORCEPROP 2 LAST CDS_LIB mstr_standard
J 0
(700 4400);
DISPLAY 0.787234 (700 4400);
PAINT MONO (700 4400);
DISPLAY INVISIBLE (700 4400);
FORCEPROP 1 LAST OFFPAGE TRUE
J 0
(1025 4275);
DISPLAY 0.936170 (1025 4275);
PAINT GREEN (1025 4275);
DISPLAY INVISIBLE (1025 4275);
FORCEPROP 1 LAST COMMENT_BODY TRUE
J 0
(650 4300);
DISPLAY 0.936170 (650 4300);
PAINT GREEN (650 4300);
DISPLAY INVISIBLE (650 4300);
FORCEPROP 2 LAST PATH I136
J 0
(925 4450);
DISPLAY 1.021277 (925 4450);
PAINT ORANGE (925 4450);
DISPLAY INVISIBLE (925 4450);
FORCEADD GND..1
R 2
(2750 1100);
FORCEPROP 3 LASTPIN (2750 1150) SIG_NAME GND\g
J 0
(2760 1160);
DISPLAY 0.659574 (2760 1160);
PAINT MONO (2760 1160);
DISPLAY INVISIBLE (2760 1160);
FORCEPROP 1 LAST VOLTAGE 0
J 0
(2750 1100);
PAINT SKYBLUE (2750 1100);
DISPLAY INVISIBLE (2750 1100);
FORCEPROP 2 LAST BOM_COST MEM
J 0
(2750 1105);
PAINT ORANGE (2750 1105);
DISPLAY INVISIBLE (2750 1105);
FORCEPROP 2 LAST CDS_LIB mstr_symbols
J 0
(2750 1100);
DISPLAY 0.787234 (2750 1100);
PAINT MONO (2750 1100);
DISPLAY INVISIBLE (2750 1100);
FORCEPROP 1 LAST SIZE 1B
J 2
(2675 1050);
DISPLAY 1.170213 (2675 1050);
PAINT GREEN (2675 1050);
DISPLAY INVISIBLE (2675 1050);
FORCEPROP 1 LAST BODY_TYPE PLUMBING
J 2
(2795 1057);
DISPLAY 0.340426 (2795 1057);
PAINT GREEN (2795 1057);
DISPLAY INVISIBLE (2795 1057);
FORCEPROP 1 LAST PATH I138
J 2
(2675 1100);
DISPLAY 0.872340 (2675 1100);
PAINT AQUA (2675 1100);
DISPLAY INVISIBLE (2675 1100);
FORCEPROP 2 LAST ROOM DDR4_CH_A
J 0
(2750 1105);
PAINT ORANGE (2750 1105);
DISPLAY INVISIBLE (2750 1105);
FORCEPROP 1 LAST HDL_POWER GND
J 2
(2750 1250);
DISPLAY 0.553191 (2750 1250);
PAINT GREEN (2750 1250);
DISPLAY INVISIBLE (2750 1250);
FORCEADD SCONN288_H44441003..3
(3450 2400);
FORCEPROP 1 LAST LOCATION J6T1
J 0
(3000 3800);
DISPLAY 0.617021 (3000 3800);
PAINT AQUA (3000 3800);
FORCEPROP 1 LAST PART_NUMBER H44441-003
J 0
(3000 1050);
DISPLAY 0.617021 (3000 1050);
PAINT BLUE (3000 1050);
FORCEPROP 1 LAST MATERIAL SCONN
J 0
(3000 3750);
DISPLAY 0.617021 (3000 3750);
PAINT SKYBLUE (3000 3750);
FORCEPROP 2 LASTPIN (2950 3550) $PN 2
J 2
(2940 3560);
DISPLAY 0.617021 (2940 3560);
PAINT ORANGE (2940 3560);
FORCEPROP 2 LASTPIN (2950 3500) $PN 4
J 2
(2940 3510);
DISPLAY 0.617021 (2940 3510);
PAINT ORANGE (2940 3510);
FORCEPROP 2 LASTPIN (2950 3450) $PN 6
J 2
(2940 3460);
DISPLAY 0.617021 (2940 3460);
PAINT ORANGE (2940 3460);
FORCEPROP 2 LASTPIN (2950 3400) $PN 9
J 2
(2940 3410);
DISPLAY 0.617021 (2940 3410);
PAINT ORANGE (2940 3410);
FORCEPROP 2 LASTPIN (2950 3350) $PN 11
J 2
(2940 3360);
DISPLAY 0.617021 (2940 3360);
PAINT ORANGE (2940 3360);
FORCEPROP 2 LASTPIN (2950 3300) $PN 13
J 2
(2940 3310);
DISPLAY 0.617021 (2940 3310);
PAINT ORANGE (2940 3310);
FORCEPROP 2 LASTPIN (2950 3250) $PN 15
J 2
(2940 3260);
DISPLAY 0.617021 (2940 3260);
PAINT ORANGE (2940 3260);
FORCEPROP 2 LASTPIN (2950 3200) $PN 17
J 2
(2940 3210);
DISPLAY 0.617021 (2940 3210);
PAINT ORANGE (2940 3210);
FORCEPROP 2 LASTPIN (2950 3150) $PN 20
J 2
(2940 3160);
DISPLAY 0.617021 (2940 3160);
PAINT ORANGE (2940 3160);
FORCEPROP 2 LASTPIN (2950 3100) $PN 22
J 2
(2940 3110);
DISPLAY 0.617021 (2940 3110);
PAINT ORANGE (2940 3110);
FORCEPROP 2 LASTPIN (2950 3050) $PN 24
J 2
(2940 3060);
DISPLAY 0.617021 (2940 3060);
PAINT ORANGE (2940 3060);
FORCEPROP 2 LASTPIN (2950 3000) $PN 26
J 2
(2940 3010);
DISPLAY 0.617021 (2940 3010);
PAINT ORANGE (2940 3010);
FORCEPROP 2 LASTPIN (2950 2950) $PN 28
J 2
(2940 2960);
DISPLAY 0.617021 (2940 2960);
PAINT ORANGE (2940 2960);
FORCEPROP 2 LASTPIN (2950 2900) $PN 31
J 2
(2940 2910);
DISPLAY 0.617021 (2940 2910);
PAINT ORANGE (2940 2910);
FORCEPROP 2 LASTPIN (2950 2850) $PN 33
J 2
(2940 2860);
DISPLAY 0.617021 (2940 2860);
PAINT ORANGE (2940 2860);
FORCEPROP 2 LASTPIN (2950 2800) $PN 35
J 2
(2940 2810);
DISPLAY 0.617021 (2940 2810);
PAINT ORANGE (2940 2810);
FORCEPROP 2 LASTPIN (2950 2750) $PN 37
J 2
(2940 2760);
DISPLAY 0.617021 (2940 2760);
PAINT ORANGE (2940 2760);
FORCEPROP 2 LASTPIN (2950 2700) $PN 39
J 2
(2940 2710);
DISPLAY 0.617021 (2940 2710);
PAINT ORANGE (2940 2710);
FORCEPROP 2 LASTPIN (2950 2600) $PN 44
J 2
(2940 2610);
DISPLAY 0.617021 (2940 2610);
PAINT ORANGE (2940 2610);
FORCEPROP 2 LASTPIN (2950 2550) $PN 46
J 2
(2940 2560);
DISPLAY 0.617021 (2940 2560);
PAINT ORANGE (2940 2560);
FORCEPROP 2 LASTPIN (2950 2500) $PN 48
J 2
(2940 2510);
DISPLAY 0.617021 (2940 2510);
PAINT ORANGE (2940 2510);
FORCEPROP 2 LASTPIN (2950 2450) $PN 50
J 2
(2940 2460);
DISPLAY 0.617021 (2940 2460);
PAINT ORANGE (2940 2460);
FORCEPROP 2 LASTPIN (2950 2400) $PN 53
J 2
(2940 2410);
DISPLAY 0.617021 (2940 2410);
PAINT ORANGE (2940 2410);
FORCEPROP 2 LASTPIN (2950 2350) $PN 55
J 2
(2940 2360);
DISPLAY 0.617021 (2940 2360);
PAINT ORANGE (2940 2360);
FORCEPROP 2 LASTPIN (2950 2300) $PN 57
J 2
(2940 2310);
DISPLAY 0.617021 (2940 2310);
PAINT ORANGE (2940 2310);
FORCEPROP 2 LASTPIN (2950 2250) $PN 94
J 2
(2940 2260);
DISPLAY 0.617021 (2940 2260);
PAINT ORANGE (2940 2260);
FORCEPROP 2 LASTPIN (2950 2200) $PN 96
J 2
(2940 2210);
DISPLAY 0.617021 (2940 2210);
PAINT ORANGE (2940 2210);
FORCEPROP 2 LASTPIN (2950 2150) $PN 98
J 2
(2940 2160);
DISPLAY 0.617021 (2940 2160);
PAINT ORANGE (2940 2160);
FORCEPROP 2 LASTPIN (2950 2100) $PN 101
J 2
(2940 2110);
DISPLAY 0.617021 (2940 2110);
PAINT ORANGE (2940 2110);
FORCEPROP 2 LASTPIN (2950 2050) $PN 103
J 2
(2940 2060);
DISPLAY 0.617021 (2940 2060);
PAINT ORANGE (2940 2060);
FORCEPROP 2 LASTPIN (2950 2000) $PN 105
J 2
(2940 2010);
DISPLAY 0.617021 (2940 2010);
PAINT ORANGE (2940 2010);
FORCEPROP 2 LASTPIN (2950 1950) $PN 107
J 2
(2940 1960);
DISPLAY 0.617021 (2940 1960);
PAINT ORANGE (2940 1960);
FORCEPROP 2 LASTPIN (2950 1900) $PN 109
J 2
(2940 1910);
DISPLAY 0.617021 (2940 1910);
PAINT ORANGE (2940 1910);
FORCEPROP 2 LASTPIN (2950 1850) $PN 112
J 2
(2940 1860);
DISPLAY 0.617021 (2940 1860);
PAINT ORANGE (2940 1860);
FORCEPROP 2 LASTPIN (2950 1800) $PN 114
J 2
(2940 1810);
DISPLAY 0.617021 (2940 1810);
PAINT ORANGE (2940 1810);
FORCEPROP 2 LASTPIN (2950 1750) $PN 116
J 2
(2940 1760);
DISPLAY 0.617021 (2940 1760);
PAINT ORANGE (2940 1760);
FORCEPROP 2 LASTPIN (2950 1700) $PN 118
J 2
(2940 1710);
DISPLAY 0.617021 (2940 1710);
PAINT ORANGE (2940 1710);
FORCEPROP 2 LASTPIN (2950 1650) $PN 120
J 2
(2940 1660);
DISPLAY 0.617021 (2940 1660);
PAINT ORANGE (2940 1660);
FORCEPROP 2 LASTPIN (2950 1600) $PN 123
J 2
(2940 1610);
DISPLAY 0.617021 (2940 1610);
PAINT ORANGE (2940 1610);
FORCEPROP 2 LASTPIN (2950 1550) $PN 125
J 2
(2940 1560);
DISPLAY 0.617021 (2940 1560);
PAINT ORANGE (2940 1560);
FORCEPROP 2 LASTPIN (2950 1500) $PN 127
J 2
(2940 1510);
DISPLAY 0.617021 (2940 1510);
PAINT ORANGE (2940 1510);
FORCEPROP 2 LASTPIN (2950 1450) $PN 129
J 2
(2940 1460);
DISPLAY 0.617021 (2940 1460);
PAINT ORANGE (2940 1460);
FORCEPROP 2 LASTPIN (2950 1400) $PN 131
J 2
(2940 1410);
DISPLAY 0.617021 (2940 1410);
PAINT ORANGE (2940 1410);
FORCEPROP 2 LASTPIN (2950 1350) $PN 134
J 2
(2940 1360);
DISPLAY 0.617021 (2940 1360);
PAINT ORANGE (2940 1360);
FORCEPROP 2 LASTPIN (2950 1300) $PN 136
J 2
(2940 1310);
DISPLAY 0.617021 (2940 1310);
PAINT ORANGE (2940 1310);
FORCEPROP 2 LASTPIN (2950 1250) $PN 138
J 2
(2940 1260);
DISPLAY 0.617021 (2940 1260);
PAINT ORANGE (2940 1260);
FORCEPROP 2 LASTPIN (3950 3550) $PN 147
J 0
(3960 3560);
DISPLAY 0.617021 (3960 3560);
PAINT ORANGE (3960 3560);
FORCEPROP 2 LASTPIN (3950 3500) $PN 149
J 0
(3960 3510);
DISPLAY 0.617021 (3960 3510);
PAINT ORANGE (3960 3510);
FORCEPROP 2 LASTPIN (3950 3450) $PN 151
J 0
(3960 3460);
DISPLAY 0.617021 (3960 3460);
PAINT ORANGE (3960 3460);
FORCEPROP 2 LASTPIN (3950 3400) $PN 154
J 0
(3960 3410);
DISPLAY 0.617021 (3960 3410);
PAINT ORANGE (3960 3410);
FORCEPROP 2 LASTPIN (3950 3350) $PN 156
J 0
(3960 3360);
DISPLAY 0.617021 (3960 3360);
PAINT ORANGE (3960 3360);
FORCEPROP 2 LASTPIN (3950 3300) $PN 158
J 0
(3960 3310);
DISPLAY 0.617021 (3960 3310);
PAINT ORANGE (3960 3310);
FORCEPROP 2 LASTPIN (3950 3250) $PN 160
J 0
(3960 3260);
DISPLAY 0.617021 (3960 3260);
PAINT ORANGE (3960 3260);
FORCEPROP 2 LASTPIN (3950 3200) $PN 162
J 0
(3960 3210);
DISPLAY 0.617021 (3960 3210);
PAINT ORANGE (3960 3210);
FORCEPROP 2 LASTPIN (3950 3150) $PN 165
J 0
(3960 3160);
DISPLAY 0.617021 (3960 3160);
PAINT ORANGE (3960 3160);
FORCEPROP 2 LASTPIN (3950 3100) $PN 167
J 0
(3960 3110);
DISPLAY 0.617021 (3960 3110);
PAINT ORANGE (3960 3110);
FORCEPROP 2 LASTPIN (3950 3050) $PN 169
J 0
(3960 3060);
DISPLAY 0.617021 (3960 3060);
PAINT ORANGE (3960 3060);
FORCEPROP 2 LASTPIN (3950 3000) $PN 171
J 0
(3960 3010);
DISPLAY 0.617021 (3960 3010);
PAINT ORANGE (3960 3010);
FORCEPROP 2 LASTPIN (3950 2950) $PN 173
J 0
(3960 2960);
DISPLAY 0.617021 (3960 2960);
PAINT ORANGE (3960 2960);
FORCEPROP 2 LASTPIN (3950 2900) $PN 176
J 0
(3960 2910);
DISPLAY 0.617021 (3960 2910);
PAINT ORANGE (3960 2910);
FORCEPROP 2 LASTPIN (3950 2850) $PN 178
J 0
(3960 2860);
DISPLAY 0.617021 (3960 2860);
PAINT ORANGE (3960 2860);
FORCEPROP 2 LASTPIN (3950 2800) $PN 180
J 0
(3960 2810);
DISPLAY 0.617021 (3960 2810);
PAINT ORANGE (3960 2810);
FORCEPROP 2 LASTPIN (3950 2750) $PN 182
J 0
(3960 2760);
DISPLAY 0.617021 (3960 2760);
PAINT ORANGE (3960 2760);
FORCEPROP 2 LASTPIN (3950 2700) $PN 184
J 0
(3960 2710);
DISPLAY 0.617021 (3960 2710);
PAINT ORANGE (3960 2710);
FORCEPROP 2 LASTPIN (3950 2650) $PN 187
J 0
(3960 2660);
DISPLAY 0.617021 (3960 2660);
PAINT ORANGE (3960 2660);
FORCEPROP 2 LASTPIN (3950 2600) $PN 189
J 0
(3960 2610);
DISPLAY 0.617021 (3960 2610);
PAINT ORANGE (3960 2610);
FORCEPROP 2 LASTPIN (3950 2550) $PN 191
J 0
(3960 2560);
DISPLAY 0.617021 (3960 2560);
PAINT ORANGE (3960 2560);
FORCEPROP 2 LASTPIN (3950 2500) $PN 193
J 0
(3960 2510);
DISPLAY 0.617021 (3960 2510);
PAINT ORANGE (3960 2510);
FORCEPROP 2 LASTPIN (3950 2450) $PN 195
J 0
(3960 2460);
DISPLAY 0.617021 (3960 2460);
PAINT ORANGE (3960 2460);
FORCEPROP 2 LASTPIN (3950 2400) $PN 198
J 0
(3960 2410);
DISPLAY 0.617021 (3960 2410);
PAINT ORANGE (3960 2410);
FORCEPROP 2 LASTPIN (3950 2350) $PN 200
J 0
(3960 2360);
DISPLAY 0.617021 (3960 2360);
PAINT ORANGE (3960 2360);
FORCEPROP 2 LASTPIN (3950 2300) $PN 202
J 0
(3960 2310);
DISPLAY 0.617021 (3960 2310);
PAINT ORANGE (3960 2310);
FORCEPROP 2 LASTPIN (3950 2250) $PN 239
J 0
(3960 2260);
DISPLAY 0.617021 (3960 2260);
PAINT ORANGE (3960 2260);
FORCEPROP 2 LASTPIN (3950 2200) $PN 241
J 0
(3960 2210);
DISPLAY 0.617021 (3960 2210);
PAINT ORANGE (3960 2210);
FORCEPROP 2 LASTPIN (3950 2150) $PN 243
J 0
(3960 2160);
DISPLAY 0.617021 (3960 2160);
PAINT ORANGE (3960 2160);
FORCEPROP 2 LASTPIN (3950 2100) $PN 246
J 0
(3960 2110);
DISPLAY 0.617021 (3960 2110);
PAINT ORANGE (3960 2110);
FORCEPROP 2 LASTPIN (3950 2050) $PN 248
J 0
(3960 2060);
DISPLAY 0.617021 (3960 2060);
PAINT ORANGE (3960 2060);
FORCEPROP 2 LASTPIN (3950 2000) $PN 250
J 0
(3960 2010);
DISPLAY 0.617021 (3960 2010);
PAINT ORANGE (3960 2010);
FORCEPROP 2 LASTPIN (3950 1950) $PN 252
J 0
(3960 1960);
DISPLAY 0.617021 (3960 1960);
PAINT ORANGE (3960 1960);
FORCEPROP 2 LASTPIN (3950 1900) $PN 254
J 0
(3960 1910);
DISPLAY 0.617021 (3960 1910);
PAINT ORANGE (3960 1910);
FORCEPROP 2 LASTPIN (3950 1850) $PN 257
J 0
(3960 1860);
DISPLAY 0.617021 (3960 1860);
PAINT ORANGE (3960 1860);
FORCEPROP 2 LASTPIN (3950 1800) $PN 259
J 0
(3960 1810);
DISPLAY 0.617021 (3960 1810);
PAINT ORANGE (3960 1810);
FORCEPROP 2 LASTPIN (3950 1750) $PN 261
J 0
(3960 1760);
DISPLAY 0.617021 (3960 1760);
PAINT ORANGE (3960 1760);
FORCEPROP 2 LASTPIN (3950 1700) $PN 263
J 0
(3960 1710);
DISPLAY 0.617021 (3960 1710);
PAINT ORANGE (3960 1710);
FORCEPROP 2 LASTPIN (3950 1650) $PN 265
J 0
(3960 1660);
DISPLAY 0.617021 (3960 1660);
PAINT ORANGE (3960 1660);
FORCEPROP 2 LASTPIN (3950 1600) $PN 268
J 0
(3960 1610);
DISPLAY 0.617021 (3960 1610);
PAINT ORANGE (3960 1610);
FORCEPROP 2 LASTPIN (3950 1550) $PN 270
J 0
(3960 1560);
DISPLAY 0.617021 (3960 1560);
PAINT ORANGE (3960 1560);
FORCEPROP 2 LASTPIN (3950 1500) $PN 272
J 0
(3960 1510);
DISPLAY 0.617021 (3960 1510);
PAINT ORANGE (3960 1510);
FORCEPROP 2 LASTPIN (3950 1450) $PN 274
J 0
(3960 1460);
DISPLAY 0.617021 (3960 1460);
PAINT ORANGE (3960 1460);
FORCEPROP 2 LASTPIN (3950 1400) $PN 276
J 0
(3960 1410);
DISPLAY 0.617021 (3960 1410);
PAINT ORANGE (3960 1410);
FORCEPROP 2 LASTPIN (3950 1350) $PN 279
J 0
(3960 1360);
DISPLAY 0.617021 (3960 1360);
PAINT ORANGE (3960 1360);
FORCEPROP 2 LASTPIN (3950 1300) $PN 281
J 0
(3960 1310);
DISPLAY 0.617021 (3960 1310);
PAINT ORANGE (3960 1310);
FORCEPROP 2 LASTPIN (3950 1250) $PN 283
J 0
(3960 1260);
DISPLAY 0.617021 (3960 1260);
PAINT ORANGE (3960 1260);
FORCEPROP 2 LASTPIN (2950 2650) $PN 42
J 2
(2940 2660);
DISPLAY 0.617021 (2940 2660);
PAINT ORANGE (2940 2660);
FORCEPROP 0 LAST BOM_SS NOPOP
J 0
(3240 3856);
DISPLAY 1.021277 (3240 3856);
PAINT BROWN (3240 3856);
DISPLAY BOTH (3240 3856);
FORCEPROP 1 LAST PACK_TYPE PIP
J 0
(3000 3850);
PAINT SKYBLUE (3000 3850);
DISPLAY INVISIBLE (3000 3850);
FORCEPROP 2 LAST BOM_COST MEM
J 0
(3450 2400);
PAINT ORANGE (3450 2400);
DISPLAY INVISIBLE (3450 2400);
FORCEPROP 2 LAST CDS_LIB mstr_sconn
J 0
(3450 2400);
PAINT ORANGE (3450 2400);
DISPLAY INVISIBLE (3450 2400);
FORCEPROP 2 LAST SEC_TYPE PIP
J 0
(3000 3850);
DISPLAY 1.021277 (3000 3850);
PAINT ORANGE (3000 3850);
DISPLAY INVISIBLE (3000 3850);
FORCEPROP 2 LAST SEC 3
J 0
(3000 3850);
DISPLAY 0.680851 (3000 3850);
PAINT MONO (3000 3850);
DISPLAY INVISIBLE (3000 3850);
FORCEPROP 2 LAST CDS_LOCATION J6T1
J 0
(3000 3800);
DISPLAY 0.617021 (3000 3800);
PAINT AQUA (3000 3800);
DISPLAY INVISIBLE (3000 3800);
FORCEPROP 1 LAST PATH I139
J 0
(3450 3750);
PAINT GREEN (3450 3750);
DISPLAY INVISIBLE (3450 3750);
FORCEPROP 2 LAST ROOM DDR4_CH_A
J 0
(3450 2400);
PAINT ORANGE (3450 2400);
DISPLAY INVISIBLE (3450 2400);
FORCEADD OFFPAGE..1
(-2100 2250);
FORCEPROP 2 LAST $XR5 48 
J 0
(-2771 2250);
DISPLAY 0.638298 (-2771 2250);
PAINT MONO (-2771 2250);
FORCEPROP 2 LAST $XR4 47 
J 0
(-2681 2250);
DISPLAY 0.638298 (-2681 2250);
PAINT MONO (-2681 2250);
FORCEPROP 2 LAST $XR3 46 
J 0
(-2591 2250);
DISPLAY 0.638298 (-2591 2250);
PAINT MONO (-2591 2250);
FORCEPROP 2 LAST $XR2 45 
J 0
(-2501 2250);
DISPLAY 0.638298 (-2501 2250);
PAINT MONO (-2501 2250);
FORCEPROP 2 LAST $XR1 43 
J 0
(-2411 2250);
DISPLAY 0.638298 (-2411 2250);
PAINT MONO (-2411 2250);
FORCEPROP 2 LAST $XR0 21 
J 0
(-2321 2250);
DISPLAY 0.638298 (-2321 2250);
PAINT MONO (-2321 2250);
FORCEPROP 2 LAST CDS_LIB mstr_standard
J 0
(-2100 2250);
DISPLAY 0.787234 (-2100 2250);
PAINT MONO (-2100 2250);
DISPLAY INVISIBLE (-2100 2250);
FORCEPROP 1 LAST OFFPAGE TRUE
J 0
(-1775 2125);
DISPLAY 0.936170 (-1775 2125);
PAINT GREEN (-1775 2125);
DISPLAY INVISIBLE (-1775 2125);
FORCEPROP 1 LAST COMMENT_BODY TRUE
J 0
(-1975 2150);
DISPLAY 0.936170 (-1975 2150);
PAINT GREEN (-1975 2150);
DISPLAY INVISIBLE (-1975 2150);
FORCEPROP 2 LAST PATH I14
J 0
(-2275 2300);
DISPLAY 1.021277 (-2275 2300);
PAINT ORANGE (-2275 2300);
DISPLAY INVISIBLE (-2275 2300);
FORCEADD TAP..6
R 2
(2350 3150);
FORCEPROP 3 LASTPIN (2300 3150) SIG_NAME M_A_DQS_DP<0>
J 0
(2310 3160);
DISPLAY 0.659574 (2310 3160);
PAINT MONO (2310 3160);
DISPLAY INVISIBLE (2310 3160);
FORCEPROP 1 LASTPIN (2300 3150) BN 0
J 2
(2350 3160);
DISPLAY 0.617021 (2350 3160);
PAINT PINK (2350 3160);
FORCEPROP 2 LAST CDS_LIB mstr_standard
J 0
(2350 3150);
DISPLAY 0.787234 (2350 3150);
PAINT MONO (2350 3150);
DISPLAY INVISIBLE (2350 3150);
FORCEPROP 1 LAST BODY_TYPE PLUMBING
J 2
(2350 3100);
DISPLAY 1.234043 (2350 3100);
PAINT GREEN (2350 3100);
DISPLAY INVISIBLE (2350 3100);
FORCEPROP 1 LAST HDL_TAP TRUE
J 2
(2025 3025);
DISPLAY 1.234043 (2025 3025);
PAINT GREEN (2025 3025);
DISPLAY INVISIBLE (2025 3025);
FORCEPROP 1 LAST PATH I142
J 2
(2352 3150);
DISPLAY 0.872340 (2352 3150);
PAINT GREEN (2352 3150);
DISPLAY INVISIBLE (2352 3150);
FORCEADD TAP..6
R 2
(2350 3250);
FORCEPROP 3 LASTPIN (2300 3250) SIG_NAME M_A_DQS_DP<1>
J 0
(2310 3260);
DISPLAY 0.659574 (2310 3260);
PAINT MONO (2310 3260);
DISPLAY INVISIBLE (2310 3260);
FORCEPROP 1 LASTPIN (2300 3250) BN 1
J 2
(2350 3260);
DISPLAY 0.617021 (2350 3260);
PAINT PINK (2350 3260);
FORCEPROP 2 LAST CDS_LIB mstr_standard
J 0
(2350 3250);
DISPLAY 0.787234 (2350 3250);
PAINT MONO (2350 3250);
DISPLAY INVISIBLE (2350 3250);
FORCEPROP 1 LAST BODY_TYPE PLUMBING
J 2
(2350 3200);
DISPLAY 1.234043 (2350 3200);
PAINT GREEN (2350 3200);
DISPLAY INVISIBLE (2350 3200);
FORCEPROP 1 LAST HDL_TAP TRUE
J 2
(2025 3125);
DISPLAY 1.234043 (2025 3125);
PAINT GREEN (2025 3125);
DISPLAY INVISIBLE (2025 3125);
FORCEPROP 1 LAST PATH I143
J 2
(2352 3250);
DISPLAY 0.872340 (2352 3250);
PAINT GREEN (2352 3250);
DISPLAY INVISIBLE (2352 3250);
FORCEADD TAP..6
R 2
(2350 3450);
FORCEPROP 3 LASTPIN (2300 3450) SIG_NAME M_A_DQS_DP<3>
J 0
(2310 3460);
DISPLAY 0.659574 (2310 3460);
PAINT MONO (2310 3460);
DISPLAY INVISIBLE (2310 3460);
FORCEPROP 1 LASTPIN (2300 3450) BN 3
J 2
(2350 3460);
DISPLAY 0.617021 (2350 3460);
PAINT PINK (2350 3460);
FORCEPROP 2 LAST CDS_LIB mstr_standard
J 0
(2350 3450);
DISPLAY 0.787234 (2350 3450);
PAINT MONO (2350 3450);
DISPLAY INVISIBLE (2350 3450);
FORCEPROP 1 LAST BODY_TYPE PLUMBING
J 2
(2350 3400);
DISPLAY 1.234043 (2350 3400);
PAINT GREEN (2350 3400);
DISPLAY INVISIBLE (2350 3400);
FORCEPROP 1 LAST HDL_TAP TRUE
J 2
(2025 3325);
DISPLAY 1.234043 (2025 3325);
PAINT GREEN (2025 3325);
DISPLAY INVISIBLE (2025 3325);
FORCEPROP 1 LAST PATH I144
J 2
(2352 3450);
DISPLAY 0.872340 (2352 3450);
PAINT GREEN (2352 3450);
DISPLAY INVISIBLE (2352 3450);
FORCEADD TAP..6
R 2
(2350 3350);
FORCEPROP 3 LASTPIN (2300 3350) SIG_NAME M_A_DQS_DP<2>
J 0
(2310 3360);
DISPLAY 0.659574 (2310 3360);
PAINT MONO (2310 3360);
DISPLAY INVISIBLE (2310 3360);
FORCEPROP 1 LASTPIN (2300 3350) BN 2
J 2
(2350 3360);
DISPLAY 0.617021 (2350 3360);
PAINT PINK (2350 3360);
FORCEPROP 2 LAST CDS_LIB mstr_standard
J 0
(2350 3350);
DISPLAY 0.787234 (2350 3350);
PAINT MONO (2350 3350);
DISPLAY INVISIBLE (2350 3350);
FORCEPROP 1 LAST BODY_TYPE PLUMBING
J 2
(2350 3300);
DISPLAY 1.234043 (2350 3300);
PAINT GREEN (2350 3300);
DISPLAY INVISIBLE (2350 3300);
FORCEPROP 1 LAST HDL_TAP TRUE
J 2
(2025 3225);
DISPLAY 1.234043 (2025 3225);
PAINT GREEN (2025 3225);
DISPLAY INVISIBLE (2025 3225);
FORCEPROP 1 LAST PATH I145
J 2
(2352 3350);
DISPLAY 0.872340 (2352 3350);
PAINT GREEN (2352 3350);
DISPLAY INVISIBLE (2352 3350);
FORCEADD TAP..6
R 2
(2550 3100);
FORCEPROP 3 LASTPIN (2500 3100) SIG_NAME M_A_DQS_DN<0>
J 0
(2510 3110);
DISPLAY 0.659574 (2510 3110);
PAINT MONO (2510 3110);
DISPLAY INVISIBLE (2510 3110);
FORCEPROP 1 LASTPIN (2500 3100) BN 0
J 2
(2550 3110);
DISPLAY 0.617021 (2550 3110);
PAINT PINK (2550 3110);
FORCEPROP 2 LAST CDS_LIB mstr_standard
J 0
(2550 3100);
DISPLAY 0.787234 (2550 3100);
PAINT MONO (2550 3100);
DISPLAY INVISIBLE (2550 3100);
FORCEPROP 1 LAST BODY_TYPE PLUMBING
J 2
(2550 3050);
DISPLAY 1.234043 (2550 3050);
PAINT GREEN (2550 3050);
DISPLAY INVISIBLE (2550 3050);
FORCEPROP 1 LAST HDL_TAP TRUE
J 2
(2225 2975);
DISPLAY 1.234043 (2225 2975);
PAINT GREEN (2225 2975);
DISPLAY INVISIBLE (2225 2975);
FORCEPROP 1 LAST PATH I146
J 2
(2552 3100);
DISPLAY 0.872340 (2552 3100);
PAINT GREEN (2552 3100);
DISPLAY INVISIBLE (2552 3100);
FORCEADD TAP..6
R 2
(2550 3200);
FORCEPROP 3 LASTPIN (2500 3200) SIG_NAME M_A_DQS_DN<1>
J 0
(2510 3210);
DISPLAY 0.659574 (2510 3210);
PAINT MONO (2510 3210);
DISPLAY INVISIBLE (2510 3210);
FORCEPROP 1 LASTPIN (2500 3200) BN 1
J 2
(2550 3210);
DISPLAY 0.617021 (2550 3210);
PAINT PINK (2550 3210);
FORCEPROP 2 LAST CDS_LIB mstr_standard
J 0
(2550 3200);
DISPLAY 0.787234 (2550 3200);
PAINT MONO (2550 3200);
DISPLAY INVISIBLE (2550 3200);
FORCEPROP 1 LAST BODY_TYPE PLUMBING
J 2
(2550 3150);
DISPLAY 1.234043 (2550 3150);
PAINT GREEN (2550 3150);
DISPLAY INVISIBLE (2550 3150);
FORCEPROP 1 LAST HDL_TAP TRUE
J 2
(2225 3075);
DISPLAY 1.234043 (2225 3075);
PAINT GREEN (2225 3075);
DISPLAY INVISIBLE (2225 3075);
FORCEPROP 1 LAST PATH I147
J 2
(2552 3200);
DISPLAY 0.872340 (2552 3200);
PAINT GREEN (2552 3200);
DISPLAY INVISIBLE (2552 3200);
FORCEADD TAP..6
R 2
(2550 3300);
FORCEPROP 3 LASTPIN (2500 3300) SIG_NAME M_A_DQS_DN<2>
J 0
(2510 3310);
DISPLAY 0.659574 (2510 3310);
PAINT MONO (2510 3310);
DISPLAY INVISIBLE (2510 3310);
FORCEPROP 1 LASTPIN (2500 3300) BN 2
J 2
(2550 3310);
DISPLAY 0.617021 (2550 3310);
PAINT PINK (2550 3310);
FORCEPROP 2 LAST CDS_LIB mstr_standard
J 0
(2550 3300);
DISPLAY 0.787234 (2550 3300);
PAINT MONO (2550 3300);
DISPLAY INVISIBLE (2550 3300);
FORCEPROP 1 LAST BODY_TYPE PLUMBING
J 2
(2550 3250);
DISPLAY 1.234043 (2550 3250);
PAINT GREEN (2550 3250);
DISPLAY INVISIBLE (2550 3250);
FORCEPROP 1 LAST HDL_TAP TRUE
J 2
(2225 3175);
DISPLAY 1.234043 (2225 3175);
PAINT GREEN (2225 3175);
DISPLAY INVISIBLE (2225 3175);
FORCEPROP 1 LAST PATH I148
J 2
(2552 3300);
DISPLAY 0.872340 (2552 3300);
PAINT GREEN (2552 3300);
DISPLAY INVISIBLE (2552 3300);
FORCEADD TAP..6
R 2
(2550 3400);
FORCEPROP 3 LASTPIN (2500 3400) SIG_NAME M_A_DQS_DN<3>
J 0
(2510 3410);
DISPLAY 0.659574 (2510 3410);
PAINT MONO (2510 3410);
DISPLAY INVISIBLE (2510 3410);
FORCEPROP 1 LASTPIN (2500 3400) BN 3
J 2
(2550 3410);
DISPLAY 0.617021 (2550 3410);
PAINT PINK (2550 3410);
FORCEPROP 2 LAST CDS_LIB mstr_standard
J 0
(2550 3400);
DISPLAY 0.787234 (2550 3400);
PAINT MONO (2550 3400);
DISPLAY INVISIBLE (2550 3400);
FORCEPROP 1 LAST BODY_TYPE PLUMBING
J 2
(2550 3350);
DISPLAY 1.234043 (2550 3350);
PAINT GREEN (2550 3350);
DISPLAY INVISIBLE (2550 3350);
FORCEPROP 1 LAST HDL_TAP TRUE
J 2
(2225 3275);
DISPLAY 1.234043 (2225 3275);
PAINT GREEN (2225 3275);
DISPLAY INVISIBLE (2225 3275);
FORCEPROP 1 LAST PATH I149
J 2
(2552 3400);
DISPLAY 0.872340 (2552 3400);
PAINT GREEN (2552 3400);
DISPLAY INVISIBLE (2552 3400);
FORCEADD OFFPAGE..6
(-2100 2350);
FORCEPROP 2 LAST $XR1 43 
J 0
(-2469 2350);
DISPLAY 0.638298 (-2469 2350);
PAINT MONO (-2469 2350);
FORCEPROP 2 LAST $XR0 23 
J 0
(-2379 2350);
DISPLAY 0.638298 (-2379 2350);
PAINT MONO (-2379 2350);
FORCEPROP 2 LAST CDS_LIB mstr_standard
J 0
(-2100 2350);
DISPLAY 0.787234 (-2100 2350);
PAINT MONO (-2100 2350);
DISPLAY INVISIBLE (-2100 2350);
FORCEPROP 1 LAST OFFPAGE TRUE
J 0
(-1775 2225);
DISPLAY 0.936170 (-1775 2225);
PAINT GREEN (-1775 2225);
DISPLAY INVISIBLE (-1775 2225);
FORCEPROP 1 LAST COMMENT_BODY TRUE
J 0
(-2000 2275);
DISPLAY 0.936170 (-2000 2275);
PAINT GREEN (-2000 2275);
DISPLAY INVISIBLE (-2000 2275);
FORCEPROP 2 LAST PATH I15
J 0
(-2375 2400);
DISPLAY 1.021277 (-2375 2400);
PAINT ORANGE (-2375 2400);
DISPLAY INVISIBLE (-2375 2400);
FORCEADD TAP..6
R 2
(2550 3500);
FORCEPROP 3 LASTPIN (2500 3500) SIG_NAME M_A_DQS_DN<4>
J 0
(2510 3510);
DISPLAY 0.659574 (2510 3510);
PAINT MONO (2510 3510);
DISPLAY INVISIBLE (2510 3510);
FORCEPROP 1 LASTPIN (2500 3500) BN 4
J 2
(2550 3510);
DISPLAY 0.617021 (2550 3510);
PAINT PINK (2550 3510);
FORCEPROP 2 LAST CDS_LIB mstr_standard
J 0
(2550 3500);
DISPLAY 0.787234 (2550 3500);
PAINT MONO (2550 3500);
DISPLAY INVISIBLE (2550 3500);
FORCEPROP 1 LAST BODY_TYPE PLUMBING
J 2
(2550 3450);
DISPLAY 1.234043 (2550 3450);
PAINT GREEN (2550 3450);
DISPLAY INVISIBLE (2550 3450);
FORCEPROP 1 LAST HDL_TAP TRUE
J 2
(2225 3375);
DISPLAY 1.234043 (2225 3375);
PAINT GREEN (2225 3375);
DISPLAY INVISIBLE (2225 3375);
FORCEPROP 1 LAST PATH I150
J 2
(2552 3500);
DISPLAY 0.872340 (2552 3500);
PAINT GREEN (2552 3500);
DISPLAY INVISIBLE (2552 3500);
FORCEADD TAP..6
R 2
(2350 3650);
FORCEPROP 3 LASTPIN (2300 3650) SIG_NAME M_A_DQS_DP<5>
J 0
(2310 3660);
DISPLAY 0.659574 (2310 3660);
PAINT MONO (2310 3660);
DISPLAY INVISIBLE (2310 3660);
FORCEPROP 1 LASTPIN (2300 3650) BN 5
J 2
(2350 3660);
DISPLAY 0.617021 (2350 3660);
PAINT PINK (2350 3660);
FORCEPROP 2 LAST CDS_LIB mstr_standard
J 0
(2350 3650);
DISPLAY 0.787234 (2350 3650);
PAINT MONO (2350 3650);
DISPLAY INVISIBLE (2350 3650);
FORCEPROP 1 LAST BODY_TYPE PLUMBING
J 2
(2350 3600);
DISPLAY 1.234043 (2350 3600);
PAINT GREEN (2350 3600);
DISPLAY INVISIBLE (2350 3600);
FORCEPROP 1 LAST HDL_TAP TRUE
J 2
(2025 3525);
DISPLAY 1.234043 (2025 3525);
PAINT GREEN (2025 3525);
DISPLAY INVISIBLE (2025 3525);
FORCEPROP 1 LAST PATH I151
J 2
(2352 3650);
DISPLAY 0.872340 (2352 3650);
PAINT GREEN (2352 3650);
DISPLAY INVISIBLE (2352 3650);
FORCEADD TAP..6
R 2
(2350 3750);
FORCEPROP 3 LASTPIN (2300 3750) SIG_NAME M_A_DQS_DP<6>
J 0
(2310 3760);
DISPLAY 0.659574 (2310 3760);
PAINT MONO (2310 3760);
DISPLAY INVISIBLE (2310 3760);
FORCEPROP 1 LASTPIN (2300 3750) BN 6
J 2
(2350 3760);
DISPLAY 0.617021 (2350 3760);
PAINT PINK (2350 3760);
FORCEPROP 2 LAST CDS_LIB mstr_standard
J 0
(2350 3750);
DISPLAY 0.787234 (2350 3750);
PAINT MONO (2350 3750);
DISPLAY INVISIBLE (2350 3750);
FORCEPROP 1 LAST BODY_TYPE PLUMBING
J 2
(2350 3700);
DISPLAY 1.234043 (2350 3700);
PAINT GREEN (2350 3700);
DISPLAY INVISIBLE (2350 3700);
FORCEPROP 1 LAST HDL_TAP TRUE
J 2
(2025 3625);
DISPLAY 1.234043 (2025 3625);
PAINT GREEN (2025 3625);
DISPLAY INVISIBLE (2025 3625);
FORCEPROP 1 LAST PATH I152
J 2
(2352 3750);
DISPLAY 0.872340 (2352 3750);
PAINT GREEN (2352 3750);
DISPLAY INVISIBLE (2352 3750);
FORCEADD TAP..6
R 2
(2350 3550);
FORCEPROP 3 LASTPIN (2300 3550) SIG_NAME M_A_DQS_DP<4>
J 0
(2310 3560);
DISPLAY 0.659574 (2310 3560);
PAINT MONO (2310 3560);
DISPLAY INVISIBLE (2310 3560);
FORCEPROP 1 LASTPIN (2300 3550) BN 4
J 2
(2350 3560);
DISPLAY 0.617021 (2350 3560);
PAINT PINK (2350 3560);
FORCEPROP 2 LAST CDS_LIB mstr_standard
J 0
(2350 3550);
DISPLAY 0.787234 (2350 3550);
PAINT MONO (2350 3550);
DISPLAY INVISIBLE (2350 3550);
FORCEPROP 1 LAST BODY_TYPE PLUMBING
J 2
(2350 3500);
DISPLAY 1.234043 (2350 3500);
PAINT GREEN (2350 3500);
DISPLAY INVISIBLE (2350 3500);
FORCEPROP 1 LAST HDL_TAP TRUE
J 2
(2025 3425);
DISPLAY 1.234043 (2025 3425);
PAINT GREEN (2025 3425);
DISPLAY INVISIBLE (2025 3425);
FORCEPROP 1 LAST PATH I153
J 2
(2352 3550);
DISPLAY 0.872340 (2352 3550);
PAINT GREEN (2352 3550);
DISPLAY INVISIBLE (2352 3550);
FORCEADD TAP..6
R 2
(2350 3950);
FORCEPROP 3 LASTPIN (2300 3950) SIG_NAME M_A_DQS_DP<8>
J 0
(2310 3960);
DISPLAY 0.659574 (2310 3960);
PAINT MONO (2310 3960);
DISPLAY INVISIBLE (2310 3960);
FORCEPROP 1 LASTPIN (2300 3950) BN 8
J 2
(2350 3960);
DISPLAY 0.617021 (2350 3960);
PAINT PINK (2350 3960);
FORCEPROP 2 LAST CDS_LIB mstr_standard
J 0
(2350 3950);
DISPLAY 0.787234 (2350 3950);
PAINT MONO (2350 3950);
DISPLAY INVISIBLE (2350 3950);
FORCEPROP 1 LAST BODY_TYPE PLUMBING
J 2
(2350 3900);
DISPLAY 1.234043 (2350 3900);
PAINT GREEN (2350 3900);
DISPLAY INVISIBLE (2350 3900);
FORCEPROP 1 LAST HDL_TAP TRUE
J 2
(2025 3825);
DISPLAY 1.234043 (2025 3825);
PAINT GREEN (2025 3825);
DISPLAY INVISIBLE (2025 3825);
FORCEPROP 1 LAST PATH I154
J 2
(2352 3950);
DISPLAY 0.872340 (2352 3950);
PAINT GREEN (2352 3950);
DISPLAY INVISIBLE (2352 3950);
FORCEADD TAP..6
R 2
(2350 3850);
FORCEPROP 3 LASTPIN (2300 3850) SIG_NAME M_A_DQS_DP<7>
J 0
(2310 3860);
DISPLAY 0.659574 (2310 3860);
PAINT MONO (2310 3860);
DISPLAY INVISIBLE (2310 3860);
FORCEPROP 1 LASTPIN (2300 3850) BN 7
J 2
(2350 3860);
DISPLAY 0.617021 (2350 3860);
PAINT PINK (2350 3860);
FORCEPROP 2 LAST CDS_LIB mstr_standard
J 0
(2350 3850);
DISPLAY 0.787234 (2350 3850);
PAINT MONO (2350 3850);
DISPLAY INVISIBLE (2350 3850);
FORCEPROP 1 LAST BODY_TYPE PLUMBING
J 2
(2350 3800);
DISPLAY 1.234043 (2350 3800);
PAINT GREEN (2350 3800);
DISPLAY INVISIBLE (2350 3800);
FORCEPROP 1 LAST HDL_TAP TRUE
J 2
(2025 3725);
DISPLAY 1.234043 (2025 3725);
PAINT GREEN (2025 3725);
DISPLAY INVISIBLE (2025 3725);
FORCEPROP 1 LAST PATH I155
J 2
(2352 3850);
DISPLAY 0.872340 (2352 3850);
PAINT GREEN (2352 3850);
DISPLAY INVISIBLE (2352 3850);
FORCEADD TAP..6
R 2
(2550 3600);
FORCEPROP 3 LASTPIN (2500 3600) SIG_NAME M_A_DQS_DN<5>
J 0
(2510 3610);
DISPLAY 0.659574 (2510 3610);
PAINT MONO (2510 3610);
DISPLAY INVISIBLE (2510 3610);
FORCEPROP 1 LASTPIN (2500 3600) BN 5
J 2
(2550 3610);
DISPLAY 0.617021 (2550 3610);
PAINT PINK (2550 3610);
FORCEPROP 2 LAST CDS_LIB mstr_standard
J 0
(2550 3600);
DISPLAY 0.787234 (2550 3600);
PAINT MONO (2550 3600);
DISPLAY INVISIBLE (2550 3600);
FORCEPROP 1 LAST BODY_TYPE PLUMBING
J 2
(2550 3550);
DISPLAY 1.234043 (2550 3550);
PAINT GREEN (2550 3550);
DISPLAY INVISIBLE (2550 3550);
FORCEPROP 1 LAST HDL_TAP TRUE
J 2
(2225 3475);
DISPLAY 1.234043 (2225 3475);
PAINT GREEN (2225 3475);
DISPLAY INVISIBLE (2225 3475);
FORCEPROP 1 LAST PATH I156
J 2
(2552 3600);
DISPLAY 0.872340 (2552 3600);
PAINT GREEN (2552 3600);
DISPLAY INVISIBLE (2552 3600);
FORCEADD TAP..6
R 2
(2550 3700);
FORCEPROP 3 LASTPIN (2500 3700) SIG_NAME M_A_DQS_DN<6>
J 0
(2510 3710);
DISPLAY 0.659574 (2510 3710);
PAINT MONO (2510 3710);
DISPLAY INVISIBLE (2510 3710);
FORCEPROP 1 LASTPIN (2500 3700) BN 6
J 2
(2550 3710);
DISPLAY 0.617021 (2550 3710);
PAINT PINK (2550 3710);
FORCEPROP 2 LAST CDS_LIB mstr_standard
J 0
(2550 3700);
DISPLAY 0.787234 (2550 3700);
PAINT MONO (2550 3700);
DISPLAY INVISIBLE (2550 3700);
FORCEPROP 1 LAST BODY_TYPE PLUMBING
J 2
(2550 3650);
DISPLAY 1.234043 (2550 3650);
PAINT GREEN (2550 3650);
DISPLAY INVISIBLE (2550 3650);
FORCEPROP 1 LAST HDL_TAP TRUE
J 2
(2225 3575);
DISPLAY 1.234043 (2225 3575);
PAINT GREEN (2225 3575);
DISPLAY INVISIBLE (2225 3575);
FORCEPROP 1 LAST PATH I157
J 2
(2552 3700);
DISPLAY 0.872340 (2552 3700);
PAINT GREEN (2552 3700);
DISPLAY INVISIBLE (2552 3700);
FORCEADD TAP..6
R 2
(2550 3800);
FORCEPROP 3 LASTPIN (2500 3800) SIG_NAME M_A_DQS_DN<7>
J 0
(2510 3810);
DISPLAY 0.659574 (2510 3810);
PAINT MONO (2510 3810);
DISPLAY INVISIBLE (2510 3810);
FORCEPROP 1 LASTPIN (2500 3800) BN 7
J 2
(2550 3810);
DISPLAY 0.617021 (2550 3810);
PAINT PINK (2550 3810);
FORCEPROP 2 LAST CDS_LIB mstr_standard
J 0
(2550 3800);
DISPLAY 0.787234 (2550 3800);
PAINT MONO (2550 3800);
DISPLAY INVISIBLE (2550 3800);
FORCEPROP 1 LAST BODY_TYPE PLUMBING
J 2
(2550 3750);
DISPLAY 1.234043 (2550 3750);
PAINT GREEN (2550 3750);
DISPLAY INVISIBLE (2550 3750);
FORCEPROP 1 LAST HDL_TAP TRUE
J 2
(2225 3675);
DISPLAY 1.234043 (2225 3675);
PAINT GREEN (2225 3675);
DISPLAY INVISIBLE (2225 3675);
FORCEPROP 1 LAST PATH I158
J 2
(2552 3800);
DISPLAY 0.872340 (2552 3800);
PAINT GREEN (2552 3800);
DISPLAY INVISIBLE (2552 3800);
FORCEADD TAP..6
R 2
(2550 3900);
FORCEPROP 3 LASTPIN (2500 3900) SIG_NAME M_A_DQS_DN<8>
J 0
(2510 3910);
DISPLAY 0.659574 (2510 3910);
PAINT MONO (2510 3910);
DISPLAY INVISIBLE (2510 3910);
FORCEPROP 1 LASTPIN (2500 3900) BN 8
J 2
(2550 3910);
DISPLAY 0.617021 (2550 3910);
PAINT PINK (2550 3910);
FORCEPROP 2 LAST CDS_LIB mstr_standard
J 0
(2550 3900);
DISPLAY 0.787234 (2550 3900);
PAINT MONO (2550 3900);
DISPLAY INVISIBLE (2550 3900);
FORCEPROP 1 LAST BODY_TYPE PLUMBING
J 2
(2550 3850);
DISPLAY 1.234043 (2550 3850);
PAINT GREEN (2550 3850);
DISPLAY INVISIBLE (2550 3850);
FORCEPROP 1 LAST HDL_TAP TRUE
J 2
(2225 3775);
DISPLAY 1.234043 (2225 3775);
PAINT GREEN (2225 3775);
DISPLAY INVISIBLE (2225 3775);
FORCEPROP 1 LAST PATH I159
J 2
(2552 3900);
DISPLAY 0.872340 (2552 3900);
PAINT GREEN (2552 3900);
DISPLAY INVISIBLE (2552 3900);
FORCEADD OFFPAGE..1
(-2100 2300);
FORCEPROP 2 LAST $XR1 43 
J 0
(-2471 2300);
DISPLAY 0.638298 (-2471 2300);
PAINT MONO (-2471 2300);
FORCEPROP 2 LAST $XR0 23 
J 0
(-2381 2300);
DISPLAY 0.638298 (-2381 2300);
PAINT MONO (-2381 2300);
FORCEPROP 2 LAST CDS_LIB mstr_standard
J 0
(-2100 2300);
DISPLAY 0.787234 (-2100 2300);
PAINT MONO (-2100 2300);
DISPLAY INVISIBLE (-2100 2300);
FORCEPROP 1 LAST OFFPAGE TRUE
J 0
(-1775 2175);
DISPLAY 0.936170 (-1775 2175);
PAINT GREEN (-1775 2175);
DISPLAY INVISIBLE (-1775 2175);
FORCEPROP 1 LAST COMMENT_BODY TRUE
J 0
(-1975 2200);
DISPLAY 0.936170 (-1975 2200);
PAINT GREEN (-1975 2200);
DISPLAY INVISIBLE (-1975 2200);
FORCEPROP 2 LAST PATH I16
J 0
(-2375 2350);
DISPLAY 1.021277 (-2375 2350);
PAINT ORANGE (-2375 2350);
DISPLAY INVISIBLE (-2375 2350);
FORCEADD TAP..6
R 2
(2550 4000);
FORCEPROP 3 LASTPIN (2500 4000) SIG_NAME M_A_DQS_DN<9>
J 0
(2510 4010);
DISPLAY 0.659574 (2510 4010);
PAINT MONO (2510 4010);
DISPLAY INVISIBLE (2510 4010);
FORCEPROP 1 LASTPIN (2500 4000) BN 9
J 2
(2550 4010);
DISPLAY 0.617021 (2550 4010);
PAINT PINK (2550 4010);
FORCEPROP 2 LAST CDS_LIB mstr_standard
J 0
(2550 4000);
DISPLAY 0.787234 (2550 4000);
PAINT MONO (2550 4000);
DISPLAY INVISIBLE (2550 4000);
FORCEPROP 1 LAST BODY_TYPE PLUMBING
J 2
(2550 3950);
DISPLAY 1.234043 (2550 3950);
PAINT GREEN (2550 3950);
DISPLAY INVISIBLE (2550 3950);
FORCEPROP 1 LAST HDL_TAP TRUE
J 2
(2225 3875);
DISPLAY 1.234043 (2225 3875);
PAINT GREEN (2225 3875);
DISPLAY INVISIBLE (2225 3875);
FORCEPROP 1 LAST PATH I160
J 2
(2552 4000);
DISPLAY 0.872340 (2552 4000);
PAINT GREEN (2552 4000);
DISPLAY INVISIBLE (2552 4000);
FORCEADD GND..1
R 2
(4150 1100);
FORCEPROP 3 LASTPIN (4150 1150) SIG_NAME GND\g
J 0
(4160 1160);
DISPLAY 0.659574 (4160 1160);
PAINT MONO (4160 1160);
DISPLAY INVISIBLE (4160 1160);
FORCEPROP 1 LAST VOLTAGE 0
J 0
(4150 1100);
PAINT SKYBLUE (4150 1100);
DISPLAY INVISIBLE (4150 1100);
FORCEPROP 1 LAST SIZE 1B
J 2
(4075 1050);
DISPLAY 1.170213 (4075 1050);
PAINT GREEN (4075 1050);
DISPLAY INVISIBLE (4075 1050);
FORCEPROP 2 LAST BOM_COST MEM
J 0
(4150 1105);
PAINT ORANGE (4150 1105);
DISPLAY INVISIBLE (4150 1105);
FORCEPROP 2 LAST CDS_LIB mstr_symbols
J 0
(4150 1100);
DISPLAY 0.787234 (4150 1100);
PAINT MONO (4150 1100);
DISPLAY INVISIBLE (4150 1100);
FORCEPROP 1 LAST BODY_TYPE PLUMBING
J 2
(4195 1057);
DISPLAY 0.340426 (4195 1057);
PAINT GREEN (4195 1057);
DISPLAY INVISIBLE (4195 1057);
FORCEPROP 1 LAST PATH I162
J 2
(4075 1100);
DISPLAY 0.872340 (4075 1100);
PAINT AQUA (4075 1100);
DISPLAY INVISIBLE (4075 1100);
FORCEPROP 2 LAST ROOM DDR4_CH_A
J 0
(4150 1105);
PAINT ORANGE (4150 1105);
DISPLAY INVISIBLE (4150 1105);
FORCEPROP 1 LAST HDL_POWER GND
J 2
(4150 1250);
DISPLAY 0.553191 (4150 1250);
PAINT GREEN (4150 1250);
DISPLAY INVISIBLE (4150 1250);
FORCEADD TAP..6
R 2
(2350 4150);
FORCEPROP 3 LASTPIN (2300 4150) SIG_NAME M_A_DQS_DP<10>
J 0
(2310 4160);
DISPLAY 0.659574 (2310 4160);
PAINT MONO (2310 4160);
DISPLAY INVISIBLE (2310 4160);
FORCEPROP 1 LASTPIN (2300 4150) BN 10
J 2
(2350 4160);
DISPLAY 0.617021 (2350 4160);
PAINT PINK (2350 4160);
FORCEPROP 2 LAST CDS_LIB mstr_standard
J 0
(2350 4150);
DISPLAY 0.787234 (2350 4150);
PAINT MONO (2350 4150);
DISPLAY INVISIBLE (2350 4150);
FORCEPROP 1 LAST BODY_TYPE PLUMBING
J 2
(2350 4100);
DISPLAY 1.234043 (2350 4100);
PAINT GREEN (2350 4100);
DISPLAY INVISIBLE (2350 4100);
FORCEPROP 1 LAST HDL_TAP TRUE
J 2
(2025 4025);
DISPLAY 1.234043 (2025 4025);
PAINT GREEN (2025 4025);
DISPLAY INVISIBLE (2025 4025);
FORCEPROP 1 LAST PATH I163
J 2
(2352 4150);
DISPLAY 0.872340 (2352 4150);
PAINT GREEN (2352 4150);
DISPLAY INVISIBLE (2352 4150);
FORCEADD TAP..6
R 2
(2350 4250);
FORCEPROP 3 LASTPIN (2300 4250) SIG_NAME M_A_DQS_DP<11>
J 0
(2310 4260);
DISPLAY 0.659574 (2310 4260);
PAINT MONO (2310 4260);
DISPLAY INVISIBLE (2310 4260);
FORCEPROP 1 LASTPIN (2300 4250) BN 11
J 2
(2350 4260);
DISPLAY 0.617021 (2350 4260);
PAINT PINK (2350 4260);
FORCEPROP 2 LAST CDS_LIB mstr_standard
J 0
(2350 4250);
DISPLAY 0.787234 (2350 4250);
PAINT MONO (2350 4250);
DISPLAY INVISIBLE (2350 4250);
FORCEPROP 1 LAST BODY_TYPE PLUMBING
J 2
(2350 4200);
DISPLAY 1.234043 (2350 4200);
PAINT GREEN (2350 4200);
DISPLAY INVISIBLE (2350 4200);
FORCEPROP 1 LAST HDL_TAP TRUE
J 2
(2025 4125);
DISPLAY 1.234043 (2025 4125);
PAINT GREEN (2025 4125);
DISPLAY INVISIBLE (2025 4125);
FORCEPROP 1 LAST PATH I164
J 2
(2352 4250);
DISPLAY 0.872340 (2352 4250);
PAINT GREEN (2352 4250);
DISPLAY INVISIBLE (2352 4250);
FORCEADD TAP..6
R 2
(2350 4050);
FORCEPROP 3 LASTPIN (2300 4050) SIG_NAME M_A_DQS_DP<9>
J 0
(2310 4060);
DISPLAY 0.659574 (2310 4060);
PAINT MONO (2310 4060);
DISPLAY INVISIBLE (2310 4060);
FORCEPROP 1 LASTPIN (2300 4050) BN 9
J 2
(2350 4060);
DISPLAY 0.617021 (2350 4060);
PAINT PINK (2350 4060);
FORCEPROP 2 LAST CDS_LIB mstr_standard
J 0
(2350 4050);
DISPLAY 0.787234 (2350 4050);
PAINT MONO (2350 4050);
DISPLAY INVISIBLE (2350 4050);
FORCEPROP 1 LAST BODY_TYPE PLUMBING
J 2
(2350 4000);
DISPLAY 1.234043 (2350 4000);
PAINT GREEN (2350 4000);
DISPLAY INVISIBLE (2350 4000);
FORCEPROP 1 LAST HDL_TAP TRUE
J 2
(2025 3925);
DISPLAY 1.234043 (2025 3925);
PAINT GREEN (2025 3925);
DISPLAY INVISIBLE (2025 3925);
FORCEPROP 1 LAST PATH I165
J 2
(2352 4050);
DISPLAY 0.872340 (2352 4050);
PAINT GREEN (2352 4050);
DISPLAY INVISIBLE (2352 4050);
FORCEADD TAP..6
R 2
(2350 4350);
FORCEPROP 3 LASTPIN (2300 4350) SIG_NAME M_A_DQS_DP<12>
J 0
(2310 4360);
DISPLAY 0.659574 (2310 4360);
PAINT MONO (2310 4360);
DISPLAY INVISIBLE (2310 4360);
FORCEPROP 1 LASTPIN (2300 4350) BN 12
J 2
(2350 4360);
DISPLAY 0.617021 (2350 4360);
PAINT PINK (2350 4360);
FORCEPROP 2 LAST CDS_LIB mstr_standard
J 0
(2350 4350);
DISPLAY 0.787234 (2350 4350);
PAINT MONO (2350 4350);
DISPLAY INVISIBLE (2350 4350);
FORCEPROP 1 LAST BODY_TYPE PLUMBING
J 2
(2350 4300);
DISPLAY 1.234043 (2350 4300);
PAINT GREEN (2350 4300);
DISPLAY INVISIBLE (2350 4300);
FORCEPROP 1 LAST HDL_TAP TRUE
J 2
(2025 4225);
DISPLAY 1.234043 (2025 4225);
PAINT GREEN (2025 4225);
DISPLAY INVISIBLE (2025 4225);
FORCEPROP 1 LAST PATH I166
J 2
(2352 4350);
DISPLAY 0.872340 (2352 4350);
PAINT GREEN (2352 4350);
DISPLAY INVISIBLE (2352 4350);
FORCEADD TAP..6
R 2
(2350 4550);
FORCEPROP 3 LASTPIN (2300 4550) SIG_NAME M_A_DQS_DP<14>
J 0
(2310 4560);
DISPLAY 0.659574 (2310 4560);
PAINT MONO (2310 4560);
DISPLAY INVISIBLE (2310 4560);
FORCEPROP 1 LASTPIN (2300 4550) BN 14
J 2
(2350 4560);
DISPLAY 0.617021 (2350 4560);
PAINT PINK (2350 4560);
FORCEPROP 2 LAST CDS_LIB mstr_standard
J 0
(2350 4550);
DISPLAY 0.787234 (2350 4550);
PAINT MONO (2350 4550);
DISPLAY INVISIBLE (2350 4550);
FORCEPROP 1 LAST BODY_TYPE PLUMBING
J 2
(2350 4500);
DISPLAY 1.234043 (2350 4500);
PAINT GREEN (2350 4500);
DISPLAY INVISIBLE (2350 4500);
FORCEPROP 1 LAST HDL_TAP TRUE
J 2
(2025 4425);
DISPLAY 1.234043 (2025 4425);
PAINT GREEN (2025 4425);
DISPLAY INVISIBLE (2025 4425);
FORCEPROP 1 LAST PATH I167
J 2
(2352 4550);
DISPLAY 0.872340 (2352 4550);
PAINT GREEN (2352 4550);
DISPLAY INVISIBLE (2352 4550);
FORCEADD TAP..6
R 2
(2350 4450);
FORCEPROP 3 LASTPIN (2300 4450) SIG_NAME M_A_DQS_DP<13>
J 0
(2310 4460);
DISPLAY 0.659574 (2310 4460);
PAINT MONO (2310 4460);
DISPLAY INVISIBLE (2310 4460);
FORCEPROP 1 LASTPIN (2300 4450) BN 13
J 2
(2350 4460);
DISPLAY 0.617021 (2350 4460);
PAINT PINK (2350 4460);
FORCEPROP 2 LAST CDS_LIB mstr_standard
J 0
(2350 4450);
DISPLAY 0.787234 (2350 4450);
PAINT MONO (2350 4450);
DISPLAY INVISIBLE (2350 4450);
FORCEPROP 1 LAST BODY_TYPE PLUMBING
J 2
(2350 4400);
DISPLAY 1.234043 (2350 4400);
PAINT GREEN (2350 4400);
DISPLAY INVISIBLE (2350 4400);
FORCEPROP 1 LAST HDL_TAP TRUE
J 2
(2025 4325);
DISPLAY 1.234043 (2025 4325);
PAINT GREEN (2025 4325);
DISPLAY INVISIBLE (2025 4325);
FORCEPROP 1 LAST PATH I168
J 2
(2352 4450);
DISPLAY 0.872340 (2352 4450);
PAINT GREEN (2352 4450);
DISPLAY INVISIBLE (2352 4450);
FORCEADD TAP..6
R 2
(2550 4100);
FORCEPROP 3 LASTPIN (2500 4100) SIG_NAME M_A_DQS_DN<10>
J 0
(2510 4110);
DISPLAY 0.659574 (2510 4110);
PAINT MONO (2510 4110);
DISPLAY INVISIBLE (2510 4110);
FORCEPROP 1 LASTPIN (2500 4100) BN 10
J 2
(2550 4110);
DISPLAY 0.617021 (2550 4110);
PAINT PINK (2550 4110);
FORCEPROP 2 LAST CDS_LIB mstr_standard
J 0
(2550 4100);
DISPLAY 0.787234 (2550 4100);
PAINT MONO (2550 4100);
DISPLAY INVISIBLE (2550 4100);
FORCEPROP 1 LAST BODY_TYPE PLUMBING
J 2
(2550 4050);
DISPLAY 1.234043 (2550 4050);
PAINT GREEN (2550 4050);
DISPLAY INVISIBLE (2550 4050);
FORCEPROP 1 LAST HDL_TAP TRUE
J 2
(2225 3975);
DISPLAY 1.234043 (2225 3975);
PAINT GREEN (2225 3975);
DISPLAY INVISIBLE (2225 3975);
FORCEPROP 1 LAST PATH I169
J 2
(2552 4100);
DISPLAY 0.872340 (2552 4100);
PAINT GREEN (2552 4100);
DISPLAY INVISIBLE (2552 4100);
FORCEADD OFFPAGE..1
(-2100 2500);
FORCEPROP 2 LAST $XR1 43 
J 0
(-2411 2500);
DISPLAY 0.638298 (-2411 2500);
PAINT MONO (-2411 2500);
FORCEPROP 2 LAST $XR0 23 
J 0
(-2321 2500);
DISPLAY 0.638298 (-2321 2500);
PAINT MONO (-2321 2500);
FORCEPROP 2 LAST CDS_LIB mstr_standard
J 0
(-2100 2500);
DISPLAY 0.787234 (-2100 2500);
PAINT MONO (-2100 2500);
DISPLAY INVISIBLE (-2100 2500);
FORCEPROP 1 LAST OFFPAGE TRUE
J 0
(-1775 2375);
DISPLAY 0.936170 (-1775 2375);
PAINT GREEN (-1775 2375);
DISPLAY INVISIBLE (-1775 2375);
FORCEPROP 1 LAST COMMENT_BODY TRUE
J 0
(-1975 2400);
DISPLAY 0.936170 (-1975 2400);
PAINT GREEN (-1975 2400);
DISPLAY INVISIBLE (-1975 2400);
FORCEPROP 2 LAST PATH I17
J 0
(-2300 2550);
DISPLAY 1.021277 (-2300 2550);
PAINT ORANGE (-2300 2550);
DISPLAY INVISIBLE (-2300 2550);
FORCEADD TAP..6
R 2
(2550 4300);
FORCEPROP 3 LASTPIN (2500 4300) SIG_NAME M_A_DQS_DN<12>
J 0
(2510 4310);
DISPLAY 0.659574 (2510 4310);
PAINT MONO (2510 4310);
DISPLAY INVISIBLE (2510 4310);
FORCEPROP 1 LASTPIN (2500 4300) BN 12
J 2
(2550 4310);
DISPLAY 0.617021 (2550 4310);
PAINT PINK (2550 4310);
FORCEPROP 2 LAST CDS_LIB mstr_standard
J 0
(2550 4300);
DISPLAY 0.787234 (2550 4300);
PAINT MONO (2550 4300);
DISPLAY INVISIBLE (2550 4300);
FORCEPROP 1 LAST BODY_TYPE PLUMBING
J 2
(2550 4250);
DISPLAY 1.234043 (2550 4250);
PAINT GREEN (2550 4250);
DISPLAY INVISIBLE (2550 4250);
FORCEPROP 1 LAST HDL_TAP TRUE
J 2
(2225 4175);
DISPLAY 1.234043 (2225 4175);
PAINT GREEN (2225 4175);
DISPLAY INVISIBLE (2225 4175);
FORCEPROP 1 LAST PATH I170
J 2
(2552 4300);
DISPLAY 0.872340 (2552 4300);
PAINT GREEN (2552 4300);
DISPLAY INVISIBLE (2552 4300);
FORCEADD TAP..6
R 2
(2550 4200);
FORCEPROP 3 LASTPIN (2500 4200) SIG_NAME M_A_DQS_DN<11>
J 0
(2510 4210);
DISPLAY 0.659574 (2510 4210);
PAINT MONO (2510 4210);
DISPLAY INVISIBLE (2510 4210);
FORCEPROP 1 LASTPIN (2500 4200) BN 11
J 2
(2550 4210);
DISPLAY 0.617021 (2550 4210);
PAINT PINK (2550 4210);
FORCEPROP 2 LAST CDS_LIB mstr_standard
J 0
(2550 4200);
DISPLAY 0.787234 (2550 4200);
PAINT MONO (2550 4200);
DISPLAY INVISIBLE (2550 4200);
FORCEPROP 1 LAST BODY_TYPE PLUMBING
J 2
(2550 4150);
DISPLAY 1.234043 (2550 4150);
PAINT GREEN (2550 4150);
DISPLAY INVISIBLE (2550 4150);
FORCEPROP 1 LAST HDL_TAP TRUE
J 2
(2225 4075);
DISPLAY 1.234043 (2225 4075);
PAINT GREEN (2225 4075);
DISPLAY INVISIBLE (2225 4075);
FORCEPROP 1 LAST PATH I171
J 2
(2552 4200);
DISPLAY 0.872340 (2552 4200);
PAINT GREEN (2552 4200);
DISPLAY INVISIBLE (2552 4200);
FORCEADD TAP..6
R 2
(2550 4400);
FORCEPROP 3 LASTPIN (2500 4400) SIG_NAME M_A_DQS_DN<13>
J 0
(2510 4410);
DISPLAY 0.659574 (2510 4410);
PAINT MONO (2510 4410);
DISPLAY INVISIBLE (2510 4410);
FORCEPROP 1 LASTPIN (2500 4400) BN 13
J 2
(2550 4410);
DISPLAY 0.617021 (2550 4410);
PAINT PINK (2550 4410);
FORCEPROP 2 LAST CDS_LIB mstr_standard
J 0
(2550 4400);
DISPLAY 0.787234 (2550 4400);
PAINT MONO (2550 4400);
DISPLAY INVISIBLE (2550 4400);
FORCEPROP 1 LAST BODY_TYPE PLUMBING
J 2
(2550 4350);
DISPLAY 1.234043 (2550 4350);
PAINT GREEN (2550 4350);
DISPLAY INVISIBLE (2550 4350);
FORCEPROP 1 LAST HDL_TAP TRUE
J 2
(2225 4275);
DISPLAY 1.234043 (2225 4275);
PAINT GREEN (2225 4275);
DISPLAY INVISIBLE (2225 4275);
FORCEPROP 1 LAST PATH I172
J 2
(2552 4400);
DISPLAY 0.872340 (2552 4400);
PAINT GREEN (2552 4400);
DISPLAY INVISIBLE (2552 4400);
FORCEADD TAP..6
R 2
(2550 4500);
FORCEPROP 3 LASTPIN (2500 4500) SIG_NAME M_A_DQS_DN<14>
J 0
(2510 4510);
DISPLAY 0.659574 (2510 4510);
PAINT MONO (2510 4510);
DISPLAY INVISIBLE (2510 4510);
FORCEPROP 1 LASTPIN (2500 4500) BN 14
J 2
(2550 4510);
DISPLAY 0.617021 (2550 4510);
PAINT PINK (2550 4510);
FORCEPROP 2 LAST CDS_LIB mstr_standard
J 0
(2550 4500);
DISPLAY 0.787234 (2550 4500);
PAINT MONO (2550 4500);
DISPLAY INVISIBLE (2550 4500);
FORCEPROP 1 LAST BODY_TYPE PLUMBING
J 2
(2550 4450);
DISPLAY 1.234043 (2550 4450);
PAINT GREEN (2550 4450);
DISPLAY INVISIBLE (2550 4450);
FORCEPROP 1 LAST HDL_TAP TRUE
J 2
(2225 4375);
DISPLAY 1.234043 (2225 4375);
PAINT GREEN (2225 4375);
DISPLAY INVISIBLE (2225 4375);
FORCEPROP 1 LAST PATH I173
J 2
(2552 4500);
DISPLAY 0.872340 (2552 4500);
PAINT GREEN (2552 4500);
DISPLAY INVISIBLE (2552 4500);
FORCEADD TAP..6
R 2
(2350 4650);
FORCEPROP 3 LASTPIN (2300 4650) SIG_NAME M_A_DQS_DP<15>
J 0
(2310 4660);
DISPLAY 0.659574 (2310 4660);
PAINT MONO (2310 4660);
DISPLAY INVISIBLE (2310 4660);
FORCEPROP 1 LASTPIN (2300 4650) BN 15
J 2
(2350 4660);
DISPLAY 0.617021 (2350 4660);
PAINT PINK (2350 4660);
FORCEPROP 2 LAST CDS_LIB mstr_standard
J 0
(2350 4650);
DISPLAY 0.787234 (2350 4650);
PAINT MONO (2350 4650);
DISPLAY INVISIBLE (2350 4650);
FORCEPROP 1 LAST BODY_TYPE PLUMBING
J 2
(2350 4600);
DISPLAY 1.234043 (2350 4600);
PAINT GREEN (2350 4600);
DISPLAY INVISIBLE (2350 4600);
FORCEPROP 1 LAST HDL_TAP TRUE
J 2
(2025 4525);
DISPLAY 1.234043 (2025 4525);
PAINT GREEN (2025 4525);
DISPLAY INVISIBLE (2025 4525);
FORCEPROP 1 LAST PATH I174
J 2
(2352 4650);
DISPLAY 0.872340 (2352 4650);
PAINT GREEN (2352 4650);
DISPLAY INVISIBLE (2352 4650);
FORCEADD TAP..6
R 2
(2350 4750);
FORCEPROP 3 LASTPIN (2300 4750) SIG_NAME M_A_DQS_DP<16>
J 0
(2310 4760);
DISPLAY 0.659574 (2310 4760);
PAINT MONO (2310 4760);
DISPLAY INVISIBLE (2310 4760);
FORCEPROP 1 LASTPIN (2300 4750) BN 16
J 2
(2350 4760);
DISPLAY 0.617021 (2350 4760);
PAINT PINK (2350 4760);
FORCEPROP 2 LAST CDS_LIB mstr_standard
J 0
(2350 4750);
DISPLAY 0.787234 (2350 4750);
PAINT MONO (2350 4750);
DISPLAY INVISIBLE (2350 4750);
FORCEPROP 1 LAST BODY_TYPE PLUMBING
J 2
(2350 4700);
DISPLAY 1.234043 (2350 4700);
PAINT GREEN (2350 4700);
DISPLAY INVISIBLE (2350 4700);
FORCEPROP 1 LAST HDL_TAP TRUE
J 2
(2025 4625);
DISPLAY 1.234043 (2025 4625);
PAINT GREEN (2025 4625);
DISPLAY INVISIBLE (2025 4625);
FORCEPROP 1 LAST PATH I175
J 2
(2352 4750);
DISPLAY 0.872340 (2352 4750);
PAINT GREEN (2352 4750);
DISPLAY INVISIBLE (2352 4750);
FORCEADD TAP..6
R 2
(2350 4850);
FORCEPROP 3 LASTPIN (2300 4850) SIG_NAME M_A_DQS_DP<17>
J 0
(2310 4860);
DISPLAY 0.659574 (2310 4860);
PAINT MONO (2310 4860);
DISPLAY INVISIBLE (2310 4860);
FORCEPROP 1 LASTPIN (2300 4850) BN 17
J 2
(2350 4860);
DISPLAY 0.617021 (2350 4860);
PAINT PINK (2350 4860);
FORCEPROP 2 LAST CDS_LIB mstr_standard
J 2
(2350 4850);
DISPLAY 0.787234 (2350 4850);
PAINT MONO (2350 4850);
DISPLAY INVISIBLE (2350 4850);
FORCEPROP 1 LAST BODY_TYPE PLUMBING
J 2
(2350 4800);
DISPLAY 1.234043 (2350 4800);
PAINT GREEN (2350 4800);
DISPLAY INVISIBLE (2350 4800);
FORCEPROP 1 LAST HDL_TAP TRUE
J 2
(2025 4725);
DISPLAY 1.234043 (2025 4725);
PAINT GREEN (2025 4725);
DISPLAY INVISIBLE (2025 4725);
FORCEPROP 1 LAST PATH I176
J 2
(2352 4850);
DISPLAY 0.872340 (2352 4850);
PAINT GREEN (2352 4850);
DISPLAY INVISIBLE (2352 4850);
FORCEADD TAP..6
R 2
(2550 4600);
FORCEPROP 3 LASTPIN (2500 4600) SIG_NAME M_A_DQS_DN<15>
J 0
(2510 4610);
DISPLAY 0.659574 (2510 4610);
PAINT MONO (2510 4610);
DISPLAY INVISIBLE (2510 4610);
FORCEPROP 1 LASTPIN (2500 4600) BN 15
J 2
(2550 4610);
DISPLAY 0.617021 (2550 4610);
PAINT PINK (2550 4610);
FORCEPROP 2 LAST CDS_LIB mstr_standard
J 0
(2550 4600);
DISPLAY 0.787234 (2550 4600);
PAINT MONO (2550 4600);
DISPLAY INVISIBLE (2550 4600);
FORCEPROP 1 LAST BODY_TYPE PLUMBING
J 2
(2550 4550);
DISPLAY 1.234043 (2550 4550);
PAINT GREEN (2550 4550);
DISPLAY INVISIBLE (2550 4550);
FORCEPROP 1 LAST HDL_TAP TRUE
J 2
(2225 4475);
DISPLAY 1.234043 (2225 4475);
PAINT GREEN (2225 4475);
DISPLAY INVISIBLE (2225 4475);
FORCEPROP 1 LAST PATH I177
J 2
(2552 4600);
DISPLAY 0.872340 (2552 4600);
PAINT GREEN (2552 4600);
DISPLAY INVISIBLE (2552 4600);
FORCEADD TAP..6
R 2
(2550 4800);
FORCEPROP 3 LASTPIN (2500 4800) SIG_NAME M_A_DQS_DN<17>
J 0
(2510 4810);
DISPLAY 0.659574 (2510 4810);
PAINT MONO (2510 4810);
DISPLAY INVISIBLE (2510 4810);
FORCEPROP 1 LASTPIN (2500 4800) BN 17
J 2
(2550 4810);
DISPLAY 0.617021 (2550 4810);
PAINT PINK (2550 4810);
FORCEPROP 2 LAST CDS_LIB mstr_standard
J 2
(2550 4800);
DISPLAY 0.787234 (2550 4800);
PAINT MONO (2550 4800);
DISPLAY INVISIBLE (2550 4800);
FORCEPROP 1 LAST BODY_TYPE PLUMBING
J 2
(2550 4750);
DISPLAY 1.234043 (2550 4750);
PAINT GREEN (2550 4750);
DISPLAY INVISIBLE (2550 4750);
FORCEPROP 1 LAST HDL_TAP TRUE
J 2
(2225 4675);
DISPLAY 1.234043 (2225 4675);
PAINT GREEN (2225 4675);
DISPLAY INVISIBLE (2225 4675);
FORCEPROP 1 LAST PATH I178
J 2
(2552 4800);
DISPLAY 0.872340 (2552 4800);
PAINT GREEN (2552 4800);
DISPLAY INVISIBLE (2552 4800);
FORCEADD TAP..6
R 2
(2550 4700);
FORCEPROP 3 LASTPIN (2500 4700) SIG_NAME M_A_DQS_DN<16>
J 0
(2510 4710);
DISPLAY 0.659574 (2510 4710);
PAINT MONO (2510 4710);
DISPLAY INVISIBLE (2510 4710);
FORCEPROP 1 LASTPIN (2500 4700) BN 16
J 2
(2550 4710);
DISPLAY 0.617021 (2550 4710);
PAINT PINK (2550 4710);
FORCEPROP 2 LAST CDS_LIB mstr_standard
J 0
(2550 4700);
DISPLAY 0.787234 (2550 4700);
PAINT MONO (2550 4700);
DISPLAY INVISIBLE (2550 4700);
FORCEPROP 1 LAST BODY_TYPE PLUMBING
J 2
(2550 4650);
DISPLAY 1.234043 (2550 4650);
PAINT GREEN (2550 4650);
DISPLAY INVISIBLE (2550 4650);
FORCEPROP 1 LAST HDL_TAP TRUE
J 2
(2225 4575);
DISPLAY 1.234043 (2225 4575);
PAINT GREEN (2225 4575);
DISPLAY INVISIBLE (2225 4575);
FORCEPROP 1 LAST PATH I179
J 2
(2552 4700);
DISPLAY 0.872340 (2552 4700);
PAINT GREEN (2552 4700);
DISPLAY INVISIBLE (2552 4700);
FORCEADD OFFPAGE..1
(-2100 2950);
FORCEPROP 2 LAST $XR1 43 
J 0
(-2411 2950);
DISPLAY 0.638298 (-2411 2950);
PAINT MONO (-2411 2950);
FORCEPROP 2 LAST $XR0 23 
J 0
(-2321 2950);
DISPLAY 0.638298 (-2321 2950);
PAINT MONO (-2321 2950);
FORCEPROP 2 LAST CDS_LIB mstr_standard
J 0
(-2100 2950);
DISPLAY 0.787234 (-2100 2950);
PAINT MONO (-2100 2950);
DISPLAY INVISIBLE (-2100 2950);
FORCEPROP 1 LAST OFFPAGE TRUE
J 0
(-1775 2825);
DISPLAY 0.936170 (-1775 2825);
PAINT GREEN (-1775 2825);
DISPLAY INVISIBLE (-1775 2825);
FORCEPROP 1 LAST COMMENT_BODY TRUE
J 0
(-1975 2850);
DISPLAY 0.936170 (-1975 2850);
PAINT GREEN (-1975 2850);
DISPLAY INVISIBLE (-1975 2850);
FORCEPROP 2 LAST PATH I18
J 0
(-2300 3000);
DISPLAY 1.021277 (-2300 3000);
PAINT ORANGE (-2300 3000);
DISPLAY INVISIBLE (-2300 3000);
FORCEADD OFFPAGE..3
(3250 4900);
FORCEPROP 2 LAST $XR1 43 
J 0
(3554 4900);
DISPLAY 0.638298 (3554 4900);
PAINT MONO (3554 4900);
FORCEPROP 2 LAST $XR0 23 
J 0
(3464 4900);
DISPLAY 0.638298 (3464 4900);
PAINT MONO (3464 4900);
FORCEPROP 2 LAST CDS_LIB mstr_standard
J 0
(3250 4900);
DISPLAY 0.787234 (3250 4900);
PAINT MONO (3250 4900);
DISPLAY INVISIBLE (3250 4900);
FORCEPROP 1 LAST OFFPAGE TRUE
J 0
(3575 4775);
DISPLAY 0.936170 (3575 4775);
PAINT GREEN (3575 4775);
DISPLAY INVISIBLE (3575 4775);
FORCEPROP 1 LAST COMMENT_BODY TRUE
J 0
(3200 4800);
DISPLAY 0.936170 (3200 4800);
PAINT GREEN (3200 4800);
DISPLAY INVISIBLE (3200 4800);
FORCEPROP 2 LAST PATH I182
J 0
(3475 4950);
DISPLAY 1.021277 (3475 4950);
PAINT ORANGE (3475 4950);
DISPLAY INVISIBLE (3475 4950);
FORCEADD OFFPAGE..3
(3250 4850);
FORCEPROP 2 LAST $XR1 43 
J 0
(3554 4850);
DISPLAY 0.638298 (3554 4850);
PAINT MONO (3554 4850);
FORCEPROP 2 LAST $XR0 23 
J 0
(3464 4850);
DISPLAY 0.638298 (3464 4850);
PAINT MONO (3464 4850);
FORCEPROP 2 LAST CDS_LIB mstr_standard
J 0
(3250 4850);
DISPLAY 0.787234 (3250 4850);
PAINT MONO (3250 4850);
DISPLAY INVISIBLE (3250 4850);
FORCEPROP 1 LAST OFFPAGE TRUE
J 0
(3575 4725);
DISPLAY 0.936170 (3575 4725);
PAINT GREEN (3575 4725);
DISPLAY INVISIBLE (3575 4725);
FORCEPROP 1 LAST COMMENT_BODY TRUE
J 0
(3200 4750);
DISPLAY 0.936170 (3200 4750);
PAINT GREEN (3200 4750);
DISPLAY INVISIBLE (3200 4750);
FORCEPROP 2 LAST PATH I183
J 0
(3475 4900);
DISPLAY 1.021277 (3475 4900);
PAINT ORANGE (3475 4900);
DISPLAY INVISIBLE (3475 4900);
FORCEADD P12V_NVDIMM_ABC..1
(2300 2725);
FORCEPROP 3 LASTPIN (2300 2675) SIG_NAME P12V_NVDIMM_ABC\g
J 0
(2310 2685);
DISPLAY 0.659574 (2310 2685);
PAINT MONO (2310 2685);
DISPLAY INVISIBLE (2310 2685);
FORCEPROP 1 LAST VOLTAGE 12.0
J 0
(2255 2682);
DISPLAY 0.340426 (2255 2682);
PAINT SKYBLUE (2255 2682);
DISPLAY INVISIBLE (2255 2682);
FORCEPROP 2 LAST CDS_LIB mstr_symbols
J 0
(2300 2725);
PAINT ORANGE (2300 2725);
DISPLAY INVISIBLE (2300 2725);
FORCEPROP 1 LAST BODY_TYPE PLUMBING
J 0
(2255 2682);
DISPLAY 0.340426 (2255 2682);
PAINT GREEN (2255 2682);
DISPLAY INVISIBLE (2255 2682);
FORCEPROP 1 LAST PATH I184
J 0
(2350 2750);
DISPLAY 0.872340 (2350 2750);
PAINT AQUA (2350 2750);
DISPLAY INVISIBLE (2350 2750);
FORCEPROP 1 LAST HDL_POWER P12V_NVDIMM_ABC
J 1
(2300 2750);
DISPLAY 0.872340 (2300 2750);
PAINT GREEN (2300 2750);
DISPLAY INVISIBLE (2300 2750);
FORCEADD OFFPAGE..1
(-2100 2900);
FORCEPROP 2 LAST $XR1 43 
J 0
(-2411 2900);
DISPLAY 0.638298 (-2411 2900);
PAINT MONO (-2411 2900);
FORCEPROP 2 LAST $XR0 23 
J 0
(-2321 2900);
DISPLAY 0.638298 (-2321 2900);
PAINT MONO (-2321 2900);
FORCEPROP 2 LAST CDS_LIB mstr_standard
J 0
(-2100 2900);
DISPLAY 0.787234 (-2100 2900);
PAINT MONO (-2100 2900);
DISPLAY INVISIBLE (-2100 2900);
FORCEPROP 1 LAST OFFPAGE TRUE
J 0
(-1775 2775);
DISPLAY 0.936170 (-1775 2775);
PAINT GREEN (-1775 2775);
DISPLAY INVISIBLE (-1775 2775);
FORCEPROP 1 LAST COMMENT_BODY TRUE
J 0
(-1975 2800);
DISPLAY 0.936170 (-1975 2800);
PAINT GREEN (-1975 2800);
DISPLAY INVISIBLE (-1975 2800);
FORCEPROP 2 LAST PATH I19
J 0
(-2300 2950);
DISPLAY 1.021277 (-2300 2950);
PAINT ORANGE (-2300 2950);
DISPLAY INVISIBLE (-2300 2950);
FORCEADD CAP_A..1
R 2
(-2650 1000);
FORCEPROP 1 LAST LOCATION C6T1
J 2
(-2700 1100);
DISPLAY 0.617021 (-2700 1100);
PAINT AQUA (-2700 1100);
FORCEPROP 1 LAST PART_NUMBER A36096-045
J 2
(-2700 850);
DISPLAY 0.617021 (-2700 850);
PAINT BLUE (-2700 850);
FORCEPROP 1 LAST VALUE 0.01UF
J 2
(-2700 1050);
DISPLAY 0.617021 (-2700 1050);
PAINT SKYBLUE (-2700 1050);
FORCEPROP 1 LAST TOLERANCE 10%
J 2
(-2700 950);
DISPLAY 0.617021 (-2700 950);
PAINT SKYBLUE (-2700 950);
FORCEPROP 1 LAST PACK_TYPE 0402V
J 2
(-2700 800);
DISPLAY 0.617021 (-2700 800);
PAINT SKYBLUE (-2700 800);
FORCEPROP 1 LAST VOLTAGE 25V
J 2
(-2700 1000);
DISPLAY 0.617021 (-2700 1000);
PAINT SKYBLUE (-2700 1000);
FORCEPROP 1 LAST MATERIAL X7R
J 2
(-2700 900);
DISPLAY 0.617021 (-2700 900);
PAINT SKYBLUE (-2700 900);
FORCEPROP 1 LASTPIN (-2650 1100) $PN 1
J 2
(-2660 1080);
DISPLAY 0.617021 (-2660 1080);
PAINT ORANGE (-2660 1080);
FORCEPROP 1 LASTPIN (-2650 900) $PN 2
J 2
(-2660 880);
DISPLAY 0.617021 (-2660 880);
PAINT ORANGE (-2660 880);
FORCEPROP 2 LAST CDS_LOCATION C6T1
J 2
(-2700 1100);
DISPLAY 0.617021 (-2700 1100);
PAINT AQUA (-2700 1100);
DISPLAY INVISIBLE (-2700 1100);
FORCEPROP 2 LAST BOM_COST MEM
J 0
(-2650 1000);
PAINT ORANGE (-2650 1000);
DISPLAY INVISIBLE (-2650 1000);
FORCEPROP 2 LAST CDS_LIB dev_discrete
J 0
(-2650 1000);
PAINT ORANGE (-2650 1000);
DISPLAY INVISIBLE (-2650 1000);
FORCEPROP 2 LAST CDS_SEC 1
J 0
(-2700 1150);
PAINT ORANGE (-2700 1150);
DISPLAY INVISIBLE (-2700 1150);
FORCEPROP 2 LAST SEC_TYPE 0402V
J 0
(-2700 1200);
DISPLAY 1.021277 (-2700 1200);
PAINT ORANGE (-2700 1200);
DISPLAY INVISIBLE (-2700 1200);
FORCEPROP 2 LAST SEC 1
J 0
(-2700 1200);
PAINT MONO (-2700 1200);
DISPLAY INVISIBLE (-2700 1200);
FORCEPROP 1 LAST PATH I2
J 2
(-2700 1150);
DISPLAY 0.978723 (-2700 1150);
PAINT WHITE (-2700 1150);
DISPLAY INVISIBLE (-2700 1150);
FORCEPROP 2 LAST ROOM DDR4_CH_A
J 0
(-2650 1000);
PAINT ORANGE (-2650 1000);
DISPLAY INVISIBLE (-2650 1000);
FORCEADD OFFPAGE..1
(-2100 2650);
FORCEPROP 2 LAST $XR1 43 
J 0
(-2411 2650);
DISPLAY 0.638298 (-2411 2650);
PAINT MONO (-2411 2650);
FORCEPROP 2 LAST $XR0 23 
J 0
(-2321 2650);
DISPLAY 0.638298 (-2321 2650);
PAINT MONO (-2321 2650);
FORCEPROP 2 LAST CDS_LIB mstr_standard
J 0
(-2100 2650);
DISPLAY 0.787234 (-2100 2650);
PAINT MONO (-2100 2650);
DISPLAY INVISIBLE (-2100 2650);
FORCEPROP 1 LAST OFFPAGE TRUE
J 0
(-1775 2525);
DISPLAY 0.936170 (-1775 2525);
PAINT GREEN (-1775 2525);
DISPLAY INVISIBLE (-1775 2525);
FORCEPROP 1 LAST COMMENT_BODY TRUE
J 0
(-1975 2550);
DISPLAY 0.936170 (-1975 2550);
PAINT GREEN (-1975 2550);
DISPLAY INVISIBLE (-1975 2550);
FORCEPROP 2 LAST PATH I20
J 0
(-2300 2700);
DISPLAY 1.021277 (-2300 2700);
PAINT ORANGE (-2300 2700);
DISPLAY INVISIBLE (-2300 2700);
FORCEADD TAP..6
(-1450 2100);
FORCEPROP 3 LASTPIN (-1400 2100) SIG_NAME M_A_ECC<3>
J 0
(-1390 2110);
DISPLAY 0.659574 (-1390 2110);
PAINT MONO (-1390 2110);
DISPLAY INVISIBLE (-1390 2110);
FORCEPROP 1 LASTPIN (-1400 2100) BN 3
J 0
(-1450 2110);
DISPLAY 0.617021 (-1450 2110);
PAINT PINK (-1450 2110);
FORCEPROP 2 LAST CDS_LIB mstr_standard
J 0
(-1450 2100);
DISPLAY 0.787234 (-1450 2100);
PAINT MONO (-1450 2100);
DISPLAY INVISIBLE (-1450 2100);
FORCEPROP 1 LAST BODY_TYPE PLUMBING
J 0
(-1450 2050);
DISPLAY 1.234043 (-1450 2050);
PAINT GREEN (-1450 2050);
DISPLAY INVISIBLE (-1450 2050);
FORCEPROP 1 LAST HDL_TAP TRUE
J 0
(-1125 1975);
DISPLAY 1.234043 (-1125 1975);
PAINT GREEN (-1125 1975);
DISPLAY INVISIBLE (-1125 1975);
FORCEPROP 1 LAST PATH I21
J 0
(-1452 2100);
DISPLAY 0.872340 (-1452 2100);
PAINT GREEN (-1452 2100);
DISPLAY INVISIBLE (-1452 2100);
FORCEADD TAP..6
(-1450 2000);
FORCEPROP 3 LASTPIN (-1400 2000) SIG_NAME M_A_ECC<1>
J 0
(-1390 2010);
DISPLAY 0.659574 (-1390 2010);
PAINT MONO (-1390 2010);
DISPLAY INVISIBLE (-1390 2010);
FORCEPROP 1 LASTPIN (-1400 2000) BN 1
J 0
(-1450 2010);
DISPLAY 0.617021 (-1450 2010);
PAINT PINK (-1450 2010);
FORCEPROP 2 LAST CDS_LIB mstr_standard
J 0
(-1450 2000);
DISPLAY 0.787234 (-1450 2000);
PAINT MONO (-1450 2000);
DISPLAY INVISIBLE (-1450 2000);
FORCEPROP 1 LAST BODY_TYPE PLUMBING
J 0
(-1450 1950);
DISPLAY 1.234043 (-1450 1950);
PAINT GREEN (-1450 1950);
DISPLAY INVISIBLE (-1450 1950);
FORCEPROP 1 LAST HDL_TAP TRUE
J 0
(-1125 1875);
DISPLAY 1.234043 (-1125 1875);
PAINT GREEN (-1125 1875);
DISPLAY INVISIBLE (-1125 1875);
FORCEPROP 1 LAST PATH I22
J 0
(-1452 2000);
DISPLAY 0.872340 (-1452 2000);
PAINT GREEN (-1452 2000);
DISPLAY INVISIBLE (-1452 2000);
FORCEADD TAP..6
(-1450 2050);
FORCEPROP 3 LASTPIN (-1400 2050) SIG_NAME M_A_ECC<2>
J 0
(-1390 2060);
DISPLAY 0.659574 (-1390 2060);
PAINT MONO (-1390 2060);
DISPLAY INVISIBLE (-1390 2060);
FORCEPROP 1 LASTPIN (-1400 2050) BN 2
J 0
(-1450 2060);
DISPLAY 0.617021 (-1450 2060);
PAINT PINK (-1450 2060);
FORCEPROP 2 LAST CDS_LIB mstr_standard
J 0
(-1450 2050);
DISPLAY 0.787234 (-1450 2050);
PAINT MONO (-1450 2050);
DISPLAY INVISIBLE (-1450 2050);
FORCEPROP 1 LAST BODY_TYPE PLUMBING
J 0
(-1450 2000);
DISPLAY 1.234043 (-1450 2000);
PAINT GREEN (-1450 2000);
DISPLAY INVISIBLE (-1450 2000);
FORCEPROP 1 LAST HDL_TAP TRUE
J 0
(-1125 1925);
DISPLAY 1.234043 (-1125 1925);
PAINT GREEN (-1125 1925);
DISPLAY INVISIBLE (-1125 1925);
FORCEPROP 1 LAST PATH I23
J 0
(-1452 2050);
DISPLAY 0.872340 (-1452 2050);
PAINT GREEN (-1452 2050);
DISPLAY INVISIBLE (-1452 2050);
FORCEADD TAP..6
(-1450 2150);
FORCEPROP 3 LASTPIN (-1400 2150) SIG_NAME M_A_ECC<4>
J 0
(-1390 2160);
DISPLAY 0.659574 (-1390 2160);
PAINT MONO (-1390 2160);
DISPLAY INVISIBLE (-1390 2160);
FORCEPROP 1 LASTPIN (-1400 2150) BN 4
J 0
(-1450 2160);
DISPLAY 0.617021 (-1450 2160);
PAINT PINK (-1450 2160);
FORCEPROP 2 LAST CDS_LIB mstr_standard
J 0
(-1450 2150);
DISPLAY 0.787234 (-1450 2150);
PAINT MONO (-1450 2150);
DISPLAY INVISIBLE (-1450 2150);
FORCEPROP 1 LAST BODY_TYPE PLUMBING
J 0
(-1450 2100);
DISPLAY 1.234043 (-1450 2100);
PAINT GREEN (-1450 2100);
DISPLAY INVISIBLE (-1450 2100);
FORCEPROP 1 LAST HDL_TAP TRUE
J 0
(-1125 2025);
DISPLAY 1.234043 (-1125 2025);
PAINT GREEN (-1125 2025);
DISPLAY INVISIBLE (-1125 2025);
FORCEPROP 1 LAST PATH I24
J 0
(-1452 2150);
DISPLAY 0.872340 (-1452 2150);
PAINT GREEN (-1452 2150);
DISPLAY INVISIBLE (-1452 2150);
FORCEADD TAP..6
(-1450 2200);
FORCEPROP 3 LASTPIN (-1400 2200) SIG_NAME M_A_ECC<5>
J 0
(-1390 2210);
DISPLAY 0.659574 (-1390 2210);
PAINT MONO (-1390 2210);
DISPLAY INVISIBLE (-1390 2210);
FORCEPROP 1 LASTPIN (-1400 2200) BN 5
J 0
(-1450 2210);
DISPLAY 0.617021 (-1450 2210);
PAINT PINK (-1450 2210);
FORCEPROP 2 LAST CDS_LIB mstr_standard
J 0
(-1450 2200);
DISPLAY 0.787234 (-1450 2200);
PAINT MONO (-1450 2200);
DISPLAY INVISIBLE (-1450 2200);
FORCEPROP 1 LAST BODY_TYPE PLUMBING
J 0
(-1450 2150);
DISPLAY 1.234043 (-1450 2150);
PAINT GREEN (-1450 2150);
DISPLAY INVISIBLE (-1450 2150);
FORCEPROP 1 LAST HDL_TAP TRUE
J 0
(-1125 2075);
DISPLAY 1.234043 (-1125 2075);
PAINT GREEN (-1125 2075);
DISPLAY INVISIBLE (-1125 2075);
FORCEPROP 1 LAST PATH I25
J 0
(-1452 2200);
DISPLAY 0.872340 (-1452 2200);
PAINT GREEN (-1452 2200);
DISPLAY INVISIBLE (-1452 2200);
FORCEADD TAP..6
(-1450 2250);
FORCEPROP 3 LASTPIN (-1400 2250) SIG_NAME M_A_ECC<6>
J 0
(-1390 2260);
DISPLAY 0.659574 (-1390 2260);
PAINT MONO (-1390 2260);
DISPLAY INVISIBLE (-1390 2260);
FORCEPROP 1 LASTPIN (-1400 2250) BN 6
J 0
(-1450 2260);
DISPLAY 0.617021 (-1450 2260);
PAINT PINK (-1450 2260);
FORCEPROP 2 LAST CDS_LIB mstr_standard
J 0
(-1450 2250);
DISPLAY 0.787234 (-1450 2250);
PAINT MONO (-1450 2250);
DISPLAY INVISIBLE (-1450 2250);
FORCEPROP 1 LAST BODY_TYPE PLUMBING
J 0
(-1450 2200);
DISPLAY 1.234043 (-1450 2200);
PAINT GREEN (-1450 2200);
DISPLAY INVISIBLE (-1450 2200);
FORCEPROP 1 LAST HDL_TAP TRUE
J 0
(-1125 2125);
DISPLAY 1.234043 (-1125 2125);
PAINT GREEN (-1125 2125);
DISPLAY INVISIBLE (-1125 2125);
FORCEPROP 1 LAST PATH I26
J 0
(-1452 2250);
DISPLAY 0.872340 (-1452 2250);
PAINT GREEN (-1452 2250);
DISPLAY INVISIBLE (-1452 2250);
FORCEADD TAP..6
(-1450 2400);
FORCEPROP 3 LASTPIN (-1400 2400) SIG_NAME M_A_ODT<2>
J 0
(-1390 2410);
DISPLAY 0.659574 (-1390 2410);
PAINT MONO (-1390 2410);
DISPLAY INVISIBLE (-1390 2410);
FORCEPROP 1 LASTPIN (-1400 2400) BN 2
J 0
(-1450 2410);
DISPLAY 0.617021 (-1450 2410);
PAINT PINK (-1450 2410);
FORCEPROP 2 LAST CDS_LIB mstr_standard
J 0
(-1450 2400);
DISPLAY 0.787234 (-1450 2400);
PAINT MONO (-1450 2400);
DISPLAY INVISIBLE (-1450 2400);
FORCEPROP 1 LAST BODY_TYPE PLUMBING
J 0
(-1450 2350);
DISPLAY 1.234043 (-1450 2350);
PAINT GREEN (-1450 2350);
DISPLAY INVISIBLE (-1450 2350);
FORCEPROP 1 LAST HDL_TAP TRUE
J 0
(-1125 2275);
DISPLAY 1.234043 (-1125 2275);
PAINT GREEN (-1125 2275);
DISPLAY INVISIBLE (-1125 2275);
FORCEPROP 1 LAST PATH I27
J 0
(-1452 2400);
DISPLAY 0.872340 (-1452 2400);
PAINT GREEN (-1452 2400);
DISPLAY INVISIBLE (-1452 2400);
FORCEADD TAP..6
(-1450 2450);
FORCEPROP 3 LASTPIN (-1400 2450) SIG_NAME M_A_ODT<3>
J 0
(-1390 2460);
DISPLAY 0.659574 (-1390 2460);
PAINT MONO (-1390 2460);
DISPLAY INVISIBLE (-1390 2460);
FORCEPROP 1 LASTPIN (-1400 2450) BN 3
J 0
(-1450 2460);
DISPLAY 0.617021 (-1450 2460);
PAINT PINK (-1450 2460);
FORCEPROP 2 LAST CDS_LIB mstr_standard
J 0
(-1450 2450);
DISPLAY 0.787234 (-1450 2450);
PAINT MONO (-1450 2450);
DISPLAY INVISIBLE (-1450 2450);
FORCEPROP 1 LAST BODY_TYPE PLUMBING
J 0
(-1450 2400);
DISPLAY 1.234043 (-1450 2400);
PAINT GREEN (-1450 2400);
DISPLAY INVISIBLE (-1450 2400);
FORCEPROP 1 LAST HDL_TAP TRUE
J 0
(-1125 2325);
DISPLAY 1.234043 (-1125 2325);
PAINT GREEN (-1125 2325);
DISPLAY INVISIBLE (-1125 2325);
FORCEPROP 1 LAST PATH I28
J 0
(-1452 2450);
DISPLAY 0.872340 (-1452 2450);
PAINT GREEN (-1452 2450);
DISPLAY INVISIBLE (-1452 2450);
FORCEADD TAP..6
(-1450 2300);
FORCEPROP 3 LASTPIN (-1400 2300) SIG_NAME M_A_ECC<7>
J 0
(-1390 2310);
DISPLAY 0.659574 (-1390 2310);
PAINT MONO (-1390 2310);
DISPLAY INVISIBLE (-1390 2310);
FORCEPROP 1 LASTPIN (-1400 2300) BN 7
J 0
(-1450 2310);
DISPLAY 0.617021 (-1450 2310);
PAINT PINK (-1450 2310);
FORCEPROP 2 LAST CDS_LIB mstr_standard
J 0
(-1450 2300);
DISPLAY 0.787234 (-1450 2300);
PAINT MONO (-1450 2300);
DISPLAY INVISIBLE (-1450 2300);
FORCEPROP 1 LAST BODY_TYPE PLUMBING
J 0
(-1450 2250);
DISPLAY 1.234043 (-1450 2250);
PAINT GREEN (-1450 2250);
DISPLAY INVISIBLE (-1450 2250);
FORCEPROP 1 LAST HDL_TAP TRUE
J 0
(-1125 2175);
DISPLAY 1.234043 (-1125 2175);
PAINT GREEN (-1125 2175);
DISPLAY INVISIBLE (-1125 2175);
FORCEPROP 1 LAST PATH I29
J 0
(-1452 2300);
DISPLAY 0.872340 (-1452 2300);
PAINT GREEN (-1452 2300);
DISPLAY INVISIBLE (-1452 2300);
FORCEADD GND..1
R 2
(-3350 1350);
FORCEPROP 3 LASTPIN (-3350 1400) SIG_NAME GND\g
J 0
(-3340 1410);
DISPLAY 0.659574 (-3340 1410);
PAINT MONO (-3340 1410);
DISPLAY INVISIBLE (-3340 1410);
FORCEPROP 1 LAST VOLTAGE 0
J 0
(-3350 1350);
PAINT SKYBLUE (-3350 1350);
DISPLAY INVISIBLE (-3350 1350);
FORCEPROP 1 LAST SIZE 1B
J 2
(-3425 1300);
DISPLAY 1.170213 (-3425 1300);
PAINT GREEN (-3425 1300);
DISPLAY INVISIBLE (-3425 1300);
FORCEPROP 2 LAST CDS_LIB mstr_symbols
J 0
(-3350 1350);
DISPLAY 0.787234 (-3350 1350);
PAINT MONO (-3350 1350);
DISPLAY INVISIBLE (-3350 1350);
FORCEPROP 2 LAST BOM_COST MEM
J 0
(-3350 1355);
PAINT ORANGE (-3350 1355);
DISPLAY INVISIBLE (-3350 1355);
FORCEPROP 1 LAST BODY_TYPE PLUMBING
J 2
(-3305 1307);
DISPLAY 0.340426 (-3305 1307);
PAINT GREEN (-3305 1307);
DISPLAY INVISIBLE (-3305 1307);
FORCEPROP 1 LAST PATH I3
J 2
(-3425 1350);
DISPLAY 0.872340 (-3425 1350);
PAINT AQUA (-3425 1350);
DISPLAY INVISIBLE (-3425 1350);
FORCEPROP 2 LAST ROOM DDR4_CH_A
J 0
(-3350 1355);
PAINT ORANGE (-3350 1355);
DISPLAY INVISIBLE (-3350 1355);
FORCEPROP 1 LAST HDL_POWER GND
J 2
(-3350 1500);
DISPLAY 0.553191 (-3350 1500);
PAINT GREEN (-3350 1500);
DISPLAY INVISIBLE (-3350 1500);
FORCEADD TAP..6
(-1650 3000);
FORCEPROP 3 LASTPIN (-1600 3000) SIG_NAME M_A_CLK_DN<2>
J 0
(-1590 3010);
DISPLAY 0.659574 (-1590 3010);
PAINT MONO (-1590 3010);
DISPLAY INVISIBLE (-1590 3010);
FORCEPROP 1 LASTPIN (-1600 3000) BN 2
J 0
(-1650 3010);
DISPLAY 0.617021 (-1650 3010);
PAINT PINK (-1650 3010);
FORCEPROP 2 LAST CDS_LIB mstr_standard
J 0
(-1650 3000);
DISPLAY 0.787234 (-1650 3000);
PAINT MONO (-1650 3000);
DISPLAY INVISIBLE (-1650 3000);
FORCEPROP 1 LAST BODY_TYPE PLUMBING
J 0
(-1650 2950);
DISPLAY 1.234043 (-1650 2950);
PAINT GREEN (-1650 2950);
DISPLAY INVISIBLE (-1650 2950);
FORCEPROP 1 LAST HDL_TAP TRUE
J 0
(-1325 2875);
DISPLAY 1.234043 (-1325 2875);
PAINT GREEN (-1325 2875);
DISPLAY INVISIBLE (-1325 2875);
FORCEPROP 1 LAST PATH I30
J 0
(-1652 3000);
DISPLAY 0.872340 (-1652 3000);
PAINT GREEN (-1652 3000);
DISPLAY INVISIBLE (-1652 3000);
FORCEADD TAP..6
(-1450 2600);
FORCEPROP 3 LASTPIN (-1400 2600) SIG_NAME M_A_CKE<3>
J 0
(-1390 2610);
DISPLAY 0.659574 (-1390 2610);
PAINT MONO (-1390 2610);
DISPLAY INVISIBLE (-1390 2610);
FORCEPROP 1 LASTPIN (-1400 2600) BN 3
J 0
(-1450 2610);
DISPLAY 0.617021 (-1450 2610);
PAINT PINK (-1450 2610);
FORCEPROP 2 LAST CDS_LIB mstr_standard
J 0
(-1450 2600);
DISPLAY 0.787234 (-1450 2600);
PAINT MONO (-1450 2600);
DISPLAY INVISIBLE (-1450 2600);
FORCEPROP 1 LAST BODY_TYPE PLUMBING
J 0
(-1450 2550);
DISPLAY 1.234043 (-1450 2550);
PAINT GREEN (-1450 2550);
DISPLAY INVISIBLE (-1450 2550);
FORCEPROP 1 LAST HDL_TAP TRUE
J 0
(-1125 2475);
DISPLAY 1.234043 (-1125 2475);
PAINT GREEN (-1125 2475);
DISPLAY INVISIBLE (-1125 2475);
FORCEPROP 1 LAST PATH I31
J 0
(-1452 2600);
DISPLAY 0.872340 (-1452 2600);
PAINT GREEN (-1452 2600);
DISPLAY INVISIBLE (-1452 2600);
FORCEADD TAP..6
(-1450 2550);
FORCEPROP 3 LASTPIN (-1400 2550) SIG_NAME M_A_CKE<2>
J 0
(-1390 2560);
DISPLAY 0.659574 (-1390 2560);
PAINT MONO (-1390 2560);
DISPLAY INVISIBLE (-1390 2560);
FORCEPROP 1 LASTPIN (-1400 2550) BN 2
J 0
(-1450 2560);
DISPLAY 0.617021 (-1450 2560);
PAINT PINK (-1450 2560);
FORCEPROP 2 LAST CDS_LIB mstr_standard
J 0
(-1450 2550);
DISPLAY 0.787234 (-1450 2550);
PAINT MONO (-1450 2550);
DISPLAY INVISIBLE (-1450 2550);
FORCEPROP 1 LAST BODY_TYPE PLUMBING
J 0
(-1450 2500);
DISPLAY 1.234043 (-1450 2500);
PAINT GREEN (-1450 2500);
DISPLAY INVISIBLE (-1450 2500);
FORCEPROP 1 LAST HDL_TAP TRUE
J 0
(-1125 2425);
DISPLAY 1.234043 (-1125 2425);
PAINT GREEN (-1125 2425);
DISPLAY INVISIBLE (-1125 2425);
FORCEPROP 1 LAST PATH I32
J 0
(-1452 2550);
DISPLAY 0.872340 (-1452 2550);
PAINT GREEN (-1452 2550);
DISPLAY INVISIBLE (-1452 2550);
FORCEADD TAP..6
(-1450 2700);
FORCEPROP 3 LASTPIN (-1400 2700) SIG_NAME M_A_CS_N<4>
J 0
(-1390 2710);
DISPLAY 0.659574 (-1390 2710);
PAINT MONO (-1390 2710);
DISPLAY INVISIBLE (-1390 2710);
FORCEPROP 1 LASTPIN (-1400 2700) BN 4
J 0
(-1450 2710);
DISPLAY 0.617021 (-1450 2710);
PAINT PINK (-1450 2710);
FORCEPROP 2 LAST CDS_LIB mstr_standard
J 0
(-1450 2700);
DISPLAY 0.787234 (-1450 2700);
PAINT MONO (-1450 2700);
DISPLAY INVISIBLE (-1450 2700);
FORCEPROP 1 LAST BODY_TYPE PLUMBING
J 0
(-1450 2650);
DISPLAY 1.234043 (-1450 2650);
PAINT GREEN (-1450 2650);
DISPLAY INVISIBLE (-1450 2650);
FORCEPROP 1 LAST HDL_TAP TRUE
J 0
(-1125 2575);
DISPLAY 1.234043 (-1125 2575);
PAINT GREEN (-1125 2575);
DISPLAY INVISIBLE (-1125 2575);
FORCEPROP 1 LAST PATH I33
J 0
(-1452 2700);
DISPLAY 0.872340 (-1452 2700);
PAINT GREEN (-1452 2700);
DISPLAY INVISIBLE (-1452 2700);
FORCEADD TAP..6
(-1450 2750);
FORCEPROP 3 LASTPIN (-1400 2750) SIG_NAME M_A_CS_N<5>
J 0
(-1390 2760);
DISPLAY 0.659574 (-1390 2760);
PAINT MONO (-1390 2760);
DISPLAY INVISIBLE (-1390 2760);
FORCEPROP 1 LASTPIN (-1400 2750) BN 5
J 0
(-1450 2760);
DISPLAY 0.617021 (-1450 2760);
PAINT PINK (-1450 2760);
FORCEPROP 2 LAST CDS_LIB mstr_standard
J 0
(-1450 2750);
DISPLAY 0.787234 (-1450 2750);
PAINT MONO (-1450 2750);
DISPLAY INVISIBLE (-1450 2750);
FORCEPROP 1 LAST BODY_TYPE PLUMBING
J 0
(-1450 2700);
DISPLAY 1.234043 (-1450 2700);
PAINT GREEN (-1450 2700);
DISPLAY INVISIBLE (-1450 2700);
FORCEPROP 1 LAST HDL_TAP TRUE
J 0
(-1125 2625);
DISPLAY 1.234043 (-1125 2625);
PAINT GREEN (-1125 2625);
DISPLAY INVISIBLE (-1125 2625);
FORCEPROP 1 LAST PATH I34
J 0
(-1452 2750);
DISPLAY 0.872340 (-1452 2750);
PAINT GREEN (-1452 2750);
DISPLAY INVISIBLE (-1452 2750);
FORCEADD TAP..6
(-1450 2850);
FORCEPROP 3 LASTPIN (-1400 2850) SIG_NAME M_A_CS_N<7>
J 0
(-1390 2860);
DISPLAY 0.659574 (-1390 2860);
PAINT MONO (-1390 2860);
DISPLAY INVISIBLE (-1390 2860);
FORCEPROP 1 LASTPIN (-1400 2850) BN 7
J 0
(-1450 2860);
DISPLAY 0.617021 (-1450 2860);
PAINT PINK (-1450 2860);
FORCEPROP 2 LAST CDS_LIB mstr_standard
J 0
(-1450 2850);
DISPLAY 0.787234 (-1450 2850);
PAINT MONO (-1450 2850);
DISPLAY INVISIBLE (-1450 2850);
FORCEPROP 1 LAST BODY_TYPE PLUMBING
J 0
(-1450 2800);
DISPLAY 1.234043 (-1450 2800);
PAINT GREEN (-1450 2800);
DISPLAY INVISIBLE (-1450 2800);
FORCEPROP 1 LAST HDL_TAP TRUE
J 0
(-1125 2725);
DISPLAY 1.234043 (-1125 2725);
PAINT GREEN (-1125 2725);
DISPLAY INVISIBLE (-1125 2725);
FORCEPROP 1 LAST PATH I35
J 0
(-1452 2850);
DISPLAY 0.872340 (-1452 2850);
PAINT GREEN (-1452 2850);
DISPLAY INVISIBLE (-1452 2850);
FORCEADD TAP..6
(-1450 2800);
FORCEPROP 3 LASTPIN (-1400 2800) SIG_NAME M_A_CS_N<6>
J 0
(-1390 2810);
DISPLAY 0.659574 (-1390 2810);
PAINT MONO (-1390 2810);
DISPLAY INVISIBLE (-1390 2810);
FORCEPROP 1 LASTPIN (-1400 2800) BN 6
J 0
(-1450 2810);
DISPLAY 0.617021 (-1450 2810);
PAINT PINK (-1450 2810);
FORCEPROP 2 LAST CDS_LIB mstr_standard
J 0
(-1450 2800);
DISPLAY 0.787234 (-1450 2800);
PAINT MONO (-1450 2800);
DISPLAY INVISIBLE (-1450 2800);
FORCEPROP 1 LAST BODY_TYPE PLUMBING
J 0
(-1450 2750);
DISPLAY 1.234043 (-1450 2750);
PAINT GREEN (-1450 2750);
DISPLAY INVISIBLE (-1450 2750);
FORCEPROP 1 LAST HDL_TAP TRUE
J 0
(-1125 2675);
DISPLAY 1.234043 (-1125 2675);
PAINT GREEN (-1125 2675);
DISPLAY INVISIBLE (-1125 2675);
FORCEPROP 1 LAST PATH I36
J 0
(-1452 2800);
DISPLAY 0.872340 (-1452 2800);
PAINT GREEN (-1452 2800);
DISPLAY INVISIBLE (-1452 2800);
FORCEADD OFFPAGE..1
(-2100 3200);
FORCEPROP 2 LAST $XR1 43 
J 0
(-2411 3200);
DISPLAY 0.638298 (-2411 3200);
PAINT MONO (-2411 3200);
FORCEPROP 2 LAST $XR0 23 
J 0
(-2321 3200);
DISPLAY 0.638298 (-2321 3200);
PAINT MONO (-2321 3200);
FORCEPROP 2 LAST CDS_LIB mstr_standard
J 0
(-2100 3200);
DISPLAY 0.787234 (-2100 3200);
PAINT MONO (-2100 3200);
DISPLAY INVISIBLE (-2100 3200);
FORCEPROP 1 LAST OFFPAGE TRUE
J 0
(-1775 3075);
DISPLAY 0.936170 (-1775 3075);
PAINT GREEN (-1775 3075);
DISPLAY INVISIBLE (-1775 3075);
FORCEPROP 1 LAST COMMENT_BODY TRUE
J 0
(-1975 3100);
DISPLAY 0.936170 (-1975 3100);
PAINT GREEN (-1975 3100);
DISPLAY INVISIBLE (-1975 3100);
FORCEPROP 2 LAST PATH I37
J 0
(-2300 3250);
DISPLAY 1.021277 (-2300 3250);
PAINT ORANGE (-2300 3250);
DISPLAY INVISIBLE (-2300 3250);
FORCEADD OFFPAGE..1
(-2100 3150);
FORCEPROP 2 LAST $XR1 43 
J 0
(-2411 3150);
DISPLAY 0.638298 (-2411 3150);
PAINT MONO (-2411 3150);
FORCEPROP 2 LAST $XR0 23 
J 0
(-2321 3150);
DISPLAY 0.638298 (-2321 3150);
PAINT MONO (-2321 3150);
FORCEPROP 2 LAST CDS_LIB mstr_standard
J 0
(-2100 3150);
DISPLAY 0.787234 (-2100 3150);
PAINT MONO (-2100 3150);
DISPLAY INVISIBLE (-2100 3150);
FORCEPROP 1 LAST OFFPAGE TRUE
J 0
(-1775 3025);
DISPLAY 0.936170 (-1775 3025);
PAINT GREEN (-1775 3025);
DISPLAY INVISIBLE (-1775 3025);
FORCEPROP 1 LAST COMMENT_BODY TRUE
J 0
(-1975 3050);
DISPLAY 0.936170 (-1975 3050);
PAINT GREEN (-1975 3050);
DISPLAY INVISIBLE (-1975 3050);
FORCEPROP 2 LAST PATH I38
J 0
(-2300 3200);
DISPLAY 1.021277 (-2300 3200);
PAINT ORANGE (-2300 3200);
DISPLAY INVISIBLE (-2300 3200);
FORCEADD OFFPAGE..1
(-2100 3350);
FORCEPROP 2 LAST $XR1 43 
J 0
(-2411 3350);
DISPLAY 0.638298 (-2411 3350);
PAINT MONO (-2411 3350);
FORCEPROP 2 LAST $XR0 23 
J 0
(-2321 3350);
DISPLAY 0.638298 (-2321 3350);
PAINT MONO (-2321 3350);
FORCEPROP 2 LAST CDS_LIB mstr_standard
J 0
(-2100 3350);
DISPLAY 0.787234 (-2100 3350);
PAINT MONO (-2100 3350);
DISPLAY INVISIBLE (-2100 3350);
FORCEPROP 1 LAST OFFPAGE TRUE
J 0
(-1775 3225);
DISPLAY 0.936170 (-1775 3225);
PAINT GREEN (-1775 3225);
DISPLAY INVISIBLE (-1775 3225);
FORCEPROP 1 LAST COMMENT_BODY TRUE
J 0
(-1975 3250);
DISPLAY 0.936170 (-1975 3250);
PAINT GREEN (-1975 3250);
DISPLAY INVISIBLE (-1975 3250);
FORCEPROP 2 LAST PATH I39
J 0
(-2300 3400);
DISPLAY 1.021277 (-2300 3400);
PAINT ORANGE (-2300 3400);
DISPLAY INVISIBLE (-2300 3400);
FORCEADD OFFPAGE..1
(-2800 1200);
FORCEPROP 2 LAST $XR1 43 
J 0
(-3141 1200);
DISPLAY 0.638298 (-3141 1200);
PAINT MONO (-3141 1200);
FORCEPROP 2 LAST $XR0 98 
J 0
(-3051 1200);
DISPLAY 0.638298 (-3051 1200);
PAINT MONO (-3051 1200);
FORCEPROP 2 LAST CDS_LIB mstr_standard
J 0
(-2800 1200);
DISPLAY 0.787234 (-2800 1200);
PAINT MONO (-2800 1200);
DISPLAY INVISIBLE (-2800 1200);
FORCEPROP 1 LAST OFFPAGE TRUE
J 0
(-2475 1075);
DISPLAY 0.936170 (-2475 1075);
PAINT GREEN (-2475 1075);
DISPLAY INVISIBLE (-2475 1075);
FORCEPROP 1 LAST COMMENT_BODY TRUE
J 0
(-2675 1100);
DISPLAY 0.936170 (-2675 1100);
PAINT GREEN (-2675 1100);
DISPLAY INVISIBLE (-2675 1100);
FORCEPROP 2 LAST PATH I4
J 0
(-3050 1250);
DISPLAY 1.021277 (-3050 1250);
PAINT ORANGE (-3050 1250);
DISPLAY INVISIBLE (-3050 1250);
FORCEADD OFFPAGE..1
(-2100 3450);
FORCEPROP 2 LAST $XR1 43 
J 0
(-2411 3450);
DISPLAY 0.638298 (-2411 3450);
PAINT MONO (-2411 3450);
FORCEPROP 2 LAST $XR0 23 
J 0
(-2321 3450);
DISPLAY 0.638298 (-2321 3450);
PAINT MONO (-2321 3450);
FORCEPROP 2 LAST CDS_LIB mstr_standard
J 0
(-2100 3450);
DISPLAY 0.787234 (-2100 3450);
PAINT MONO (-2100 3450);
DISPLAY INVISIBLE (-2100 3450);
FORCEPROP 1 LAST OFFPAGE TRUE
J 0
(-1775 3325);
DISPLAY 0.936170 (-1775 3325);
PAINT GREEN (-1775 3325);
DISPLAY INVISIBLE (-1775 3325);
FORCEPROP 1 LAST COMMENT_BODY TRUE
J 0
(-1975 3350);
DISPLAY 0.936170 (-1975 3350);
PAINT GREEN (-1975 3350);
DISPLAY INVISIBLE (-1975 3350);
FORCEPROP 2 LAST PATH I40
J 0
(-2300 3500);
DISPLAY 1.021277 (-2300 3500);
PAINT ORANGE (-2300 3500);
DISPLAY INVISIBLE (-2300 3500);
FORCEADD TAP..6
(-1650 3100);
FORCEPROP 3 LASTPIN (-1600 3100) SIG_NAME M_A_CLK_DN<3>
J 0
(-1590 3110);
DISPLAY 0.659574 (-1590 3110);
PAINT MONO (-1590 3110);
DISPLAY INVISIBLE (-1590 3110);
FORCEPROP 1 LASTPIN (-1600 3100) BN 3
J 0
(-1650 3110);
DISPLAY 0.617021 (-1650 3110);
PAINT PINK (-1650 3110);
FORCEPROP 2 LAST CDS_LIB mstr_standard
J 0
(-1650 3100);
DISPLAY 0.787234 (-1650 3100);
PAINT MONO (-1650 3100);
DISPLAY INVISIBLE (-1650 3100);
FORCEPROP 1 LAST BODY_TYPE PLUMBING
J 0
(-1650 3050);
DISPLAY 1.234043 (-1650 3050);
PAINT GREEN (-1650 3050);
DISPLAY INVISIBLE (-1650 3050);
FORCEPROP 1 LAST HDL_TAP TRUE
J 0
(-1325 2975);
DISPLAY 1.234043 (-1325 2975);
PAINT GREEN (-1325 2975);
DISPLAY INVISIBLE (-1325 2975);
FORCEPROP 1 LAST PATH I41
J 0
(-1652 3100);
DISPLAY 0.872340 (-1652 3100);
PAINT GREEN (-1652 3100);
DISPLAY INVISIBLE (-1652 3100);
FORCEADD TAP..6
(-1450 3150);
FORCEPROP 3 LASTPIN (-1400 3150) SIG_NAME M_A_CLK_DP<3>
J 0
(-1390 3160);
DISPLAY 0.659574 (-1390 3160);
PAINT MONO (-1390 3160);
DISPLAY INVISIBLE (-1390 3160);
FORCEPROP 1 LASTPIN (-1400 3150) BN 3
J 0
(-1450 3160);
DISPLAY 0.617021 (-1450 3160);
PAINT PINK (-1450 3160);
FORCEPROP 2 LAST CDS_LIB mstr_standard
J 0
(-1450 3150);
DISPLAY 0.787234 (-1450 3150);
PAINT MONO (-1450 3150);
DISPLAY INVISIBLE (-1450 3150);
FORCEPROP 1 LAST BODY_TYPE PLUMBING
J 0
(-1450 3100);
DISPLAY 1.234043 (-1450 3100);
PAINT GREEN (-1450 3100);
DISPLAY INVISIBLE (-1450 3100);
FORCEPROP 1 LAST HDL_TAP TRUE
J 0
(-1125 3025);
DISPLAY 1.234043 (-1125 3025);
PAINT GREEN (-1125 3025);
DISPLAY INVISIBLE (-1125 3025);
FORCEPROP 1 LAST PATH I42
J 0
(-1452 3150);
DISPLAY 0.872340 (-1452 3150);
PAINT GREEN (-1452 3150);
DISPLAY INVISIBLE (-1452 3150);
FORCEADD TAP..6
(-1450 3050);
FORCEPROP 3 LASTPIN (-1400 3050) SIG_NAME M_A_CLK_DP<2>
J 0
(-1390 3060);
DISPLAY 0.659574 (-1390 3060);
PAINT MONO (-1390 3060);
DISPLAY INVISIBLE (-1390 3060);
FORCEPROP 1 LASTPIN (-1400 3050) BN 2
J 0
(-1450 3060);
DISPLAY 0.617021 (-1450 3060);
PAINT PINK (-1450 3060);
FORCEPROP 2 LAST CDS_LIB mstr_standard
J 0
(-1450 3050);
DISPLAY 0.787234 (-1450 3050);
PAINT MONO (-1450 3050);
DISPLAY INVISIBLE (-1450 3050);
FORCEPROP 1 LAST BODY_TYPE PLUMBING
J 0
(-1450 3000);
DISPLAY 1.234043 (-1450 3000);
PAINT GREEN (-1450 3000);
DISPLAY INVISIBLE (-1450 3000);
FORCEPROP 1 LAST HDL_TAP TRUE
J 0
(-1125 2925);
DISPLAY 1.234043 (-1125 2925);
PAINT GREEN (-1125 2925);
DISPLAY INVISIBLE (-1125 2925);
FORCEPROP 1 LAST PATH I43
J 0
(-1452 3050);
DISPLAY 0.872340 (-1452 3050);
PAINT GREEN (-1452 3050);
DISPLAY INVISIBLE (-1452 3050);
FORCEADD TAP..6
(-1450 3250);
FORCEPROP 3 LASTPIN (-1400 3250) SIG_NAME M_A_BG<0>
J 0
(-1390 3260);
DISPLAY 0.659574 (-1390 3260);
PAINT MONO (-1390 3260);
DISPLAY INVISIBLE (-1390 3260);
FORCEPROP 1 LASTPIN (-1400 3250) BN 0
J 0
(-1450 3260);
DISPLAY 0.617021 (-1450 3260);
PAINT PINK (-1450 3260);
FORCEPROP 2 LAST CDS_LIB mstr_standard
J 0
(-1450 3250);
DISPLAY 0.787234 (-1450 3250);
PAINT MONO (-1450 3250);
DISPLAY INVISIBLE (-1450 3250);
FORCEPROP 1 LAST BODY_TYPE PLUMBING
J 0
(-1450 3200);
DISPLAY 1.234043 (-1450 3200);
PAINT GREEN (-1450 3200);
DISPLAY INVISIBLE (-1450 3200);
FORCEPROP 1 LAST HDL_TAP TRUE
J 0
(-1125 3125);
DISPLAY 1.234043 (-1125 3125);
PAINT GREEN (-1125 3125);
DISPLAY INVISIBLE (-1125 3125);
FORCEPROP 1 LAST PATH I44
J 0
(-1452 3250);
DISPLAY 0.872340 (-1452 3250);
PAINT GREEN (-1452 3250);
DISPLAY INVISIBLE (-1452 3250);
FORCEADD TAP..6
(-1450 3300);
FORCEPROP 3 LASTPIN (-1400 3300) SIG_NAME M_A_BG<1>
J 0
(-1390 3310);
DISPLAY 0.659574 (-1390 3310);
PAINT MONO (-1390 3310);
DISPLAY INVISIBLE (-1390 3310);
FORCEPROP 1 LASTPIN (-1400 3300) BN 1
J 0
(-1450 3310);
DISPLAY 0.617021 (-1450 3310);
PAINT PINK (-1450 3310);
FORCEPROP 2 LAST CDS_LIB mstr_standard
J 0
(-1450 3300);
DISPLAY 0.787234 (-1450 3300);
PAINT MONO (-1450 3300);
DISPLAY INVISIBLE (-1450 3300);
FORCEPROP 1 LAST BODY_TYPE PLUMBING
J 0
(-1450 3250);
DISPLAY 1.234043 (-1450 3250);
PAINT GREEN (-1450 3250);
DISPLAY INVISIBLE (-1450 3250);
FORCEPROP 1 LAST HDL_TAP TRUE
J 0
(-1125 3175);
DISPLAY 1.234043 (-1125 3175);
PAINT GREEN (-1125 3175);
DISPLAY INVISIBLE (-1125 3175);
FORCEPROP 1 LAST PATH I45
J 0
(-1452 3300);
DISPLAY 0.872340 (-1452 3300);
PAINT GREEN (-1452 3300);
DISPLAY INVISIBLE (-1452 3300);
FORCEADD TAP..6
(-1450 3400);
FORCEPROP 3 LASTPIN (-1400 3400) SIG_NAME M_A_BA<1>
J 0
(-1390 3410);
DISPLAY 0.659574 (-1390 3410);
PAINT MONO (-1390 3410);
DISPLAY INVISIBLE (-1390 3410);
FORCEPROP 1 LASTPIN (-1400 3400) BN 1
J 0
(-1450 3410);
DISPLAY 0.617021 (-1450 3410);
PAINT PINK (-1450 3410);
FORCEPROP 2 LAST CDS_LIB mstr_standard
J 0
(-1450 3400);
DISPLAY 0.787234 (-1450 3400);
PAINT MONO (-1450 3400);
DISPLAY INVISIBLE (-1450 3400);
FORCEPROP 1 LAST BODY_TYPE PLUMBING
J 0
(-1450 3350);
DISPLAY 1.234043 (-1450 3350);
PAINT GREEN (-1450 3350);
DISPLAY INVISIBLE (-1450 3350);
FORCEPROP 1 LAST HDL_TAP TRUE
J 0
(-1125 3275);
DISPLAY 1.234043 (-1125 3275);
PAINT GREEN (-1125 3275);
DISPLAY INVISIBLE (-1125 3275);
FORCEPROP 1 LAST PATH I46
J 0
(-1452 3400);
DISPLAY 0.872340 (-1452 3400);
PAINT GREEN (-1452 3400);
DISPLAY INVISIBLE (-1452 3400);
FORCEADD TAP..6
(-1450 3350);
FORCEPROP 3 LASTPIN (-1400 3350) SIG_NAME M_A_BA<0>
J 0
(-1390 3360);
DISPLAY 0.659574 (-1390 3360);
PAINT MONO (-1390 3360);
DISPLAY INVISIBLE (-1390 3360);
FORCEPROP 1 LASTPIN (-1400 3350) BN 0
J 0
(-1450 3360);
DISPLAY 0.617021 (-1450 3360);
PAINT PINK (-1450 3360);
FORCEPROP 2 LAST CDS_LIB mstr_standard
J 0
(-1450 3350);
DISPLAY 0.787234 (-1450 3350);
PAINT MONO (-1450 3350);
DISPLAY INVISIBLE (-1450 3350);
FORCEPROP 1 LAST BODY_TYPE PLUMBING
J 0
(-1450 3300);
DISPLAY 1.234043 (-1450 3300);
PAINT GREEN (-1450 3300);
DISPLAY INVISIBLE (-1450 3300);
FORCEPROP 1 LAST HDL_TAP TRUE
J 0
(-1125 3225);
DISPLAY 1.234043 (-1125 3225);
PAINT GREEN (-1125 3225);
DISPLAY INVISIBLE (-1125 3225);
FORCEPROP 1 LAST PATH I47
J 0
(-1452 3350);
DISPLAY 0.872340 (-1452 3350);
PAINT GREEN (-1452 3350);
DISPLAY INVISIBLE (-1452 3350);
FORCEADD TAP..6
(-1450 3500);
FORCEPROP 3 LASTPIN (-1400 3500) SIG_NAME M_A_MA<0>
J 0
(-1390 3510);
DISPLAY 0.659574 (-1390 3510);
PAINT MONO (-1390 3510);
DISPLAY INVISIBLE (-1390 3510);
FORCEPROP 1 LASTPIN (-1400 3500) BN 0
J 0
(-1450 3510);
DISPLAY 0.617021 (-1450 3510);
PAINT PINK (-1450 3510);
FORCEPROP 2 LAST CDS_LIB mstr_standard
J 2
(-1450 3500);
DISPLAY 0.787234 (-1450 3500);
PAINT MONO (-1450 3500);
DISPLAY INVISIBLE (-1450 3500);
FORCEPROP 1 LAST BODY_TYPE PLUMBING
J 0
(-1450 3450);
DISPLAY 1.234043 (-1450 3450);
PAINT GREEN (-1450 3450);
DISPLAY INVISIBLE (-1450 3450);
FORCEPROP 1 LAST HDL_TAP TRUE
J 0
(-1125 3375);
DISPLAY 1.234043 (-1125 3375);
PAINT GREEN (-1125 3375);
DISPLAY INVISIBLE (-1125 3375);
FORCEPROP 1 LAST PATH I48
J 0
(-1452 3500);
DISPLAY 0.872340 (-1452 3500);
PAINT GREEN (-1452 3500);
DISPLAY INVISIBLE (-1452 3500);
FORCEADD TAP..6
(-1450 3700);
FORCEPROP 3 LASTPIN (-1400 3700) SIG_NAME M_A_MA<4>
J 0
(-1390 3710);
DISPLAY 0.659574 (-1390 3710);
PAINT MONO (-1390 3710);
DISPLAY INVISIBLE (-1390 3710);
FORCEPROP 1 LASTPIN (-1400 3700) BN 4
J 0
(-1450 3710);
DISPLAY 0.617021 (-1450 3710);
PAINT PINK (-1450 3710);
FORCEPROP 2 LAST CDS_LIB mstr_standard
J 2
(-1450 3700);
DISPLAY 0.787234 (-1450 3700);
PAINT MONO (-1450 3700);
DISPLAY INVISIBLE (-1450 3700);
FORCEPROP 1 LAST BODY_TYPE PLUMBING
J 0
(-1450 3650);
DISPLAY 1.234043 (-1450 3650);
PAINT GREEN (-1450 3650);
DISPLAY INVISIBLE (-1450 3650);
FORCEPROP 1 LAST HDL_TAP TRUE
J 0
(-1125 3575);
DISPLAY 1.234043 (-1125 3575);
PAINT GREEN (-1125 3575);
DISPLAY INVISIBLE (-1125 3575);
FORCEPROP 1 LAST PATH I49
J 0
(-1452 3700);
DISPLAY 0.872340 (-1452 3700);
PAINT GREEN (-1452 3700);
DISPLAY INVISIBLE (-1452 3700);
FORCEADD PVPP_ABC..1
(-3350 1700);
FORCEPROP 3 LASTPIN (-3350 1650) SIG_NAME PVPP_ABC\g
J 0
(-3340 1660);
DISPLAY 0.659574 (-3340 1660);
PAINT MONO (-3340 1660);
DISPLAY INVISIBLE (-3340 1660);
FORCEPROP 1 LAST VOLTAGE 2.5V
J 0
(-3395 1657);
DISPLAY 0.340426 (-3395 1657);
PAINT SKYBLUE (-3395 1657);
DISPLAY INVISIBLE (-3395 1657);
FORCEPROP 0 LAST BOM_COST MEM
J 0
(-3350 1800);
PAINT ORANGE (-3350 1800);
DISPLAY INVISIBLE (-3350 1800);
FORCEPROP 2 LAST CDS_LIB mstr_symbols
J 0
(-3350 1700);
PAINT ORANGE (-3350 1700);
DISPLAY INVISIBLE (-3350 1700);
FORCEPROP 1 LAST BODY_TYPE PLUMBING
J 0
(-3395 1657);
DISPLAY 0.340426 (-3395 1657);
PAINT GREEN (-3395 1657);
DISPLAY INVISIBLE (-3395 1657);
FORCEPROP 1 LAST PATH I5
J 0
(-3300 1725);
DISPLAY 0.872340 (-3300 1725);
PAINT AQUA (-3300 1725);
DISPLAY INVISIBLE (-3300 1725);
FORCEPROP 2 LAST ROOM DDR4_CH_A
J 0
(-3350 1800);
PAINT ORANGE (-3350 1800);
DISPLAY INVISIBLE (-3350 1800);
FORCEPROP 1 LAST HDL_POWER PVPP_ABC
J 1
(-3350 1750);
DISPLAY 0.872340 (-3350 1750);
PAINT GREEN (-3350 1750);
DISPLAY INVISIBLE (-3350 1750);
FORCEADD TAP..6
(-1450 3600);
FORCEPROP 3 LASTPIN (-1400 3600) SIG_NAME M_A_MA<2>
J 0
(-1390 3610);
DISPLAY 0.659574 (-1390 3610);
PAINT MONO (-1390 3610);
DISPLAY INVISIBLE (-1390 3610);
FORCEPROP 1 LASTPIN (-1400 3600) BN 2
J 0
(-1450 3610);
DISPLAY 0.617021 (-1450 3610);
PAINT PINK (-1450 3610);
FORCEPROP 2 LAST CDS_LIB mstr_standard
J 2
(-1450 3600);
DISPLAY 0.787234 (-1450 3600);
PAINT MONO (-1450 3600);
DISPLAY INVISIBLE (-1450 3600);
FORCEPROP 1 LAST BODY_TYPE PLUMBING
J 0
(-1450 3550);
DISPLAY 1.234043 (-1450 3550);
PAINT GREEN (-1450 3550);
DISPLAY INVISIBLE (-1450 3550);
FORCEPROP 1 LAST HDL_TAP TRUE
J 0
(-1125 3475);
DISPLAY 1.234043 (-1125 3475);
PAINT GREEN (-1125 3475);
DISPLAY INVISIBLE (-1125 3475);
FORCEPROP 1 LAST PATH I50
J 0
(-1452 3600);
DISPLAY 0.872340 (-1452 3600);
PAINT GREEN (-1452 3600);
DISPLAY INVISIBLE (-1452 3600);
FORCEADD TAP..6
(-1450 3550);
FORCEPROP 3 LASTPIN (-1400 3550) SIG_NAME M_A_MA<1>
J 0
(-1390 3560);
DISPLAY 0.659574 (-1390 3560);
PAINT MONO (-1390 3560);
DISPLAY INVISIBLE (-1390 3560);
FORCEPROP 1 LASTPIN (-1400 3550) BN 1
J 0
(-1450 3560);
DISPLAY 0.617021 (-1450 3560);
PAINT PINK (-1450 3560);
FORCEPROP 2 LAST CDS_LIB mstr_standard
J 2
(-1450 3550);
DISPLAY 0.787234 (-1450 3550);
PAINT MONO (-1450 3550);
DISPLAY INVISIBLE (-1450 3550);
FORCEPROP 1 LAST BODY_TYPE PLUMBING
J 0
(-1450 3500);
DISPLAY 1.234043 (-1450 3500);
PAINT GREEN (-1450 3500);
DISPLAY INVISIBLE (-1450 3500);
FORCEPROP 1 LAST HDL_TAP TRUE
J 0
(-1125 3425);
DISPLAY 1.234043 (-1125 3425);
PAINT GREEN (-1125 3425);
DISPLAY INVISIBLE (-1125 3425);
FORCEPROP 1 LAST PATH I51
J 0
(-1452 3550);
DISPLAY 0.872340 (-1452 3550);
PAINT GREEN (-1452 3550);
DISPLAY INVISIBLE (-1452 3550);
FORCEADD TAP..6
(-1450 3650);
FORCEPROP 3 LASTPIN (-1400 3650) SIG_NAME M_A_MA<3>
J 0
(-1390 3660);
DISPLAY 0.659574 (-1390 3660);
PAINT MONO (-1390 3660);
DISPLAY INVISIBLE (-1390 3660);
FORCEPROP 1 LASTPIN (-1400 3650) BN 3
J 0
(-1450 3660);
DISPLAY 0.617021 (-1450 3660);
PAINT PINK (-1450 3660);
FORCEPROP 2 LAST CDS_LIB mstr_standard
J 2
(-1450 3650);
DISPLAY 0.787234 (-1450 3650);
PAINT MONO (-1450 3650);
DISPLAY INVISIBLE (-1450 3650);
FORCEPROP 1 LAST BODY_TYPE PLUMBING
J 0
(-1450 3600);
DISPLAY 1.234043 (-1450 3600);
PAINT GREEN (-1450 3600);
DISPLAY INVISIBLE (-1450 3600);
FORCEPROP 1 LAST HDL_TAP TRUE
J 0
(-1125 3525);
DISPLAY 1.234043 (-1125 3525);
PAINT GREEN (-1125 3525);
DISPLAY INVISIBLE (-1125 3525);
FORCEPROP 1 LAST PATH I52
J 0
(-1452 3650);
DISPLAY 0.872340 (-1452 3650);
PAINT GREEN (-1452 3650);
DISPLAY INVISIBLE (-1452 3650);
FORCEADD TAP..6
(-1450 3750);
FORCEPROP 3 LASTPIN (-1400 3750) SIG_NAME M_A_MA<5>
J 0
(-1390 3760);
DISPLAY 0.659574 (-1390 3760);
PAINT MONO (-1390 3760);
DISPLAY INVISIBLE (-1390 3760);
FORCEPROP 1 LASTPIN (-1400 3750) BN 5
J 0
(-1450 3760);
DISPLAY 0.617021 (-1450 3760);
PAINT PINK (-1450 3760);
FORCEPROP 2 LAST CDS_LIB mstr_standard
J 2
(-1450 3750);
DISPLAY 0.787234 (-1450 3750);
PAINT MONO (-1450 3750);
DISPLAY INVISIBLE (-1450 3750);
FORCEPROP 1 LAST BODY_TYPE PLUMBING
J 0
(-1450 3700);
DISPLAY 1.234043 (-1450 3700);
PAINT GREEN (-1450 3700);
DISPLAY INVISIBLE (-1450 3700);
FORCEPROP 1 LAST HDL_TAP TRUE
J 0
(-1125 3625);
DISPLAY 1.234043 (-1125 3625);
PAINT GREEN (-1125 3625);
DISPLAY INVISIBLE (-1125 3625);
FORCEPROP 1 LAST PATH I53
J 0
(-1452 3750);
DISPLAY 0.872340 (-1452 3750);
PAINT GREEN (-1452 3750);
DISPLAY INVISIBLE (-1452 3750);
FORCEADD TAP..6
(-1450 3900);
FORCEPROP 3 LASTPIN (-1400 3900) SIG_NAME M_A_MA<8>
J 0
(-1390 3910);
DISPLAY 0.659574 (-1390 3910);
PAINT MONO (-1390 3910);
DISPLAY INVISIBLE (-1390 3910);
FORCEPROP 1 LASTPIN (-1400 3900) BN 8
J 0
(-1450 3910);
DISPLAY 0.617021 (-1450 3910);
PAINT PINK (-1450 3910);
FORCEPROP 2 LAST CDS_LIB mstr_standard
J 2
(-1450 3900);
DISPLAY 0.787234 (-1450 3900);
PAINT MONO (-1450 3900);
DISPLAY INVISIBLE (-1450 3900);
FORCEPROP 1 LAST BODY_TYPE PLUMBING
J 0
(-1450 3850);
DISPLAY 1.234043 (-1450 3850);
PAINT GREEN (-1450 3850);
DISPLAY INVISIBLE (-1450 3850);
FORCEPROP 1 LAST HDL_TAP TRUE
J 0
(-1125 3775);
DISPLAY 1.234043 (-1125 3775);
PAINT GREEN (-1125 3775);
DISPLAY INVISIBLE (-1125 3775);
FORCEPROP 1 LAST PATH I54
J 0
(-1452 3900);
DISPLAY 0.872340 (-1452 3900);
PAINT GREEN (-1452 3900);
DISPLAY INVISIBLE (-1452 3900);
FORCEADD TAP..6
(-1450 3800);
FORCEPROP 3 LASTPIN (-1400 3800) SIG_NAME M_A_MA<6>
J 0
(-1390 3810);
DISPLAY 0.659574 (-1390 3810);
PAINT MONO (-1390 3810);
DISPLAY INVISIBLE (-1390 3810);
FORCEPROP 1 LASTPIN (-1400 3800) BN 6
J 0
(-1450 3810);
DISPLAY 0.617021 (-1450 3810);
PAINT PINK (-1450 3810);
FORCEPROP 2 LAST CDS_LIB mstr_standard
J 2
(-1450 3800);
DISPLAY 0.787234 (-1450 3800);
PAINT MONO (-1450 3800);
DISPLAY INVISIBLE (-1450 3800);
FORCEPROP 1 LAST BODY_TYPE PLUMBING
J 0
(-1450 3750);
DISPLAY 1.234043 (-1450 3750);
PAINT GREEN (-1450 3750);
DISPLAY INVISIBLE (-1450 3750);
FORCEPROP 1 LAST HDL_TAP TRUE
J 0
(-1125 3675);
DISPLAY 1.234043 (-1125 3675);
PAINT GREEN (-1125 3675);
DISPLAY INVISIBLE (-1125 3675);
FORCEPROP 1 LAST PATH I55
J 0
(-1452 3800);
DISPLAY 0.872340 (-1452 3800);
PAINT GREEN (-1452 3800);
DISPLAY INVISIBLE (-1452 3800);
FORCEADD TAP..6
(-1450 3850);
FORCEPROP 3 LASTPIN (-1400 3850) SIG_NAME M_A_MA<7>
J 0
(-1390 3860);
DISPLAY 0.659574 (-1390 3860);
PAINT MONO (-1390 3860);
DISPLAY INVISIBLE (-1390 3860);
FORCEPROP 1 LASTPIN (-1400 3850) BN 7
J 0
(-1450 3860);
DISPLAY 0.617021 (-1450 3860);
PAINT PINK (-1450 3860);
FORCEPROP 2 LAST CDS_LIB mstr_standard
J 2
(-1450 3850);
DISPLAY 0.787234 (-1450 3850);
PAINT MONO (-1450 3850);
DISPLAY INVISIBLE (-1450 3850);
FORCEPROP 1 LAST BODY_TYPE PLUMBING
J 0
(-1450 3800);
DISPLAY 1.234043 (-1450 3800);
PAINT GREEN (-1450 3800);
DISPLAY INVISIBLE (-1450 3800);
FORCEPROP 1 LAST HDL_TAP TRUE
J 0
(-1125 3725);
DISPLAY 1.234043 (-1125 3725);
PAINT GREEN (-1125 3725);
DISPLAY INVISIBLE (-1125 3725);
FORCEPROP 1 LAST PATH I56
J 0
(-1452 3850);
DISPLAY 0.872340 (-1452 3850);
PAINT GREEN (-1452 3850);
DISPLAY INVISIBLE (-1452 3850);
FORCEADD TAP..6
(-1450 3950);
FORCEPROP 3 LASTPIN (-1400 3950) SIG_NAME M_A_MA<9>
J 0
(-1390 3960);
DISPLAY 0.659574 (-1390 3960);
PAINT MONO (-1390 3960);
DISPLAY INVISIBLE (-1390 3960);
FORCEPROP 1 LASTPIN (-1400 3950) BN 9
J 0
(-1450 3960);
DISPLAY 0.617021 (-1450 3960);
PAINT PINK (-1450 3960);
FORCEPROP 2 LAST CDS_LIB mstr_standard
J 2
(-1450 3950);
DISPLAY 0.787234 (-1450 3950);
PAINT MONO (-1450 3950);
DISPLAY INVISIBLE (-1450 3950);
FORCEPROP 1 LAST BODY_TYPE PLUMBING
J 0
(-1450 3900);
DISPLAY 1.234043 (-1450 3900);
PAINT GREEN (-1450 3900);
DISPLAY INVISIBLE (-1450 3900);
FORCEPROP 1 LAST HDL_TAP TRUE
J 0
(-1125 3825);
DISPLAY 1.234043 (-1125 3825);
PAINT GREEN (-1125 3825);
DISPLAY INVISIBLE (-1125 3825);
FORCEPROP 1 LAST PATH I57
J 0
(-1452 3950);
DISPLAY 0.872340 (-1452 3950);
PAINT GREEN (-1452 3950);
DISPLAY INVISIBLE (-1452 3950);
FORCEADD TAP..6
(-1450 4000);
FORCEPROP 3 LASTPIN (-1400 4000) SIG_NAME M_A_MA<10>
J 0
(-1390 4010);
DISPLAY 0.659574 (-1390 4010);
PAINT MONO (-1390 4010);
DISPLAY INVISIBLE (-1390 4010);
FORCEPROP 1 LASTPIN (-1400 4000) BN 10
J 0
(-1450 4010);
DISPLAY 0.617021 (-1450 4010);
PAINT PINK (-1450 4010);
FORCEPROP 2 LAST CDS_LIB mstr_standard
J 2
(-1450 4000);
DISPLAY 0.787234 (-1450 4000);
PAINT MONO (-1450 4000);
DISPLAY INVISIBLE (-1450 4000);
FORCEPROP 1 LAST BODY_TYPE PLUMBING
J 0
(-1450 3950);
DISPLAY 1.234043 (-1450 3950);
PAINT GREEN (-1450 3950);
DISPLAY INVISIBLE (-1450 3950);
FORCEPROP 1 LAST HDL_TAP TRUE
J 0
(-1125 3875);
DISPLAY 1.234043 (-1125 3875);
PAINT GREEN (-1125 3875);
DISPLAY INVISIBLE (-1125 3875);
FORCEPROP 1 LAST PATH I58
J 0
(-1452 4000);
DISPLAY 0.872340 (-1452 4000);
PAINT GREEN (-1452 4000);
DISPLAY INVISIBLE (-1452 4000);
FORCEADD TAP..6
R 2
(100 1200);
FORCEPROP 3 LASTPIN (50 1200) SIG_NAME M_A_DQ<0>
J 0
(60 1210);
DISPLAY 0.659574 (60 1210);
PAINT MONO (60 1210);
DISPLAY INVISIBLE (60 1210);
FORCEPROP 1 LASTPIN (50 1200) BN 0
J 2
(100 1210);
DISPLAY 0.617021 (100 1210);
PAINT PINK (100 1210);
FORCEPROP 2 LAST CDS_LIB mstr_standard
J 2
(100 1200);
DISPLAY 0.787234 (100 1200);
PAINT MONO (100 1200);
DISPLAY INVISIBLE (100 1200);
FORCEPROP 1 LAST BODY_TYPE PLUMBING
J 2
(100 1150);
DISPLAY 1.234043 (100 1150);
PAINT GREEN (100 1150);
DISPLAY INVISIBLE (100 1150);
FORCEPROP 1 LAST HDL_TAP TRUE
J 2
(-225 1075);
DISPLAY 1.234043 (-225 1075);
PAINT GREEN (-225 1075);
DISPLAY INVISIBLE (-225 1075);
FORCEPROP 1 LAST PATH I59
J 2
(102 1200);
DISPLAY 0.872340 (102 1200);
PAINT GREEN (102 1200);
DISPLAY INVISIBLE (102 1200);
FORCEADD OFFPAGE..1
(-2300 1650);
FORCEPROP 2 LAST $XR1 43 
J 0
(-2671 1650);
DISPLAY 0.638298 (-2671 1650);
PAINT MONO (-2671 1650);
FORCEPROP 2 LAST $XR0 23 
J 0
(-2581 1650);
DISPLAY 0.638298 (-2581 1650);
PAINT MONO (-2581 1650);
FORCEPROP 2 LAST CDS_LIB mstr_standard
J 0
(-2300 1650);
DISPLAY 0.787234 (-2300 1650);
PAINT MONO (-2300 1650);
DISPLAY INVISIBLE (-2300 1650);
FORCEPROP 1 LAST OFFPAGE TRUE
J 0
(-1975 1525);
DISPLAY 0.936170 (-1975 1525);
PAINT GREEN (-1975 1525);
DISPLAY INVISIBLE (-1975 1525);
FORCEPROP 1 LAST COMMENT_BODY TRUE
J 0
(-2175 1550);
DISPLAY 0.936170 (-2175 1550);
PAINT GREEN (-2175 1550);
DISPLAY INVISIBLE (-2175 1550);
FORCEPROP 2 LAST PATH I6
J 0
(-2575 1700);
DISPLAY 1.021277 (-2575 1700);
PAINT ORANGE (-2575 1700);
DISPLAY INVISIBLE (-2575 1700);
FORCEADD TAP..6
R 2
(100 1300);
FORCEPROP 3 LASTPIN (50 1300) SIG_NAME M_A_DQ<2>
J 0
(60 1310);
DISPLAY 0.659574 (60 1310);
PAINT MONO (60 1310);
DISPLAY INVISIBLE (60 1310);
FORCEPROP 1 LASTPIN (50 1300) BN 2
J 2
(100 1310);
DISPLAY 0.617021 (100 1310);
PAINT PINK (100 1310);
FORCEPROP 2 LAST CDS_LIB mstr_standard
J 2
(100 1300);
DISPLAY 0.787234 (100 1300);
PAINT MONO (100 1300);
DISPLAY INVISIBLE (100 1300);
FORCEPROP 1 LAST BODY_TYPE PLUMBING
J 2
(100 1250);
DISPLAY 1.234043 (100 1250);
PAINT GREEN (100 1250);
DISPLAY INVISIBLE (100 1250);
FORCEPROP 1 LAST HDL_TAP TRUE
J 2
(-225 1175);
DISPLAY 1.234043 (-225 1175);
PAINT GREEN (-225 1175);
DISPLAY INVISIBLE (-225 1175);
FORCEPROP 1 LAST PATH I60
J 2
(102 1300);
DISPLAY 0.872340 (102 1300);
PAINT GREEN (102 1300);
DISPLAY INVISIBLE (102 1300);
FORCEADD TAP..6
R 2
(100 1250);
FORCEPROP 3 LASTPIN (50 1250) SIG_NAME M_A_DQ<1>
J 0
(60 1260);
DISPLAY 0.659574 (60 1260);
PAINT MONO (60 1260);
DISPLAY INVISIBLE (60 1260);
FORCEPROP 1 LASTPIN (50 1250) BN 1
J 2
(100 1260);
DISPLAY 0.617021 (100 1260);
PAINT PINK (100 1260);
FORCEPROP 2 LAST CDS_LIB mstr_standard
J 2
(100 1250);
DISPLAY 0.787234 (100 1250);
PAINT MONO (100 1250);
DISPLAY INVISIBLE (100 1250);
FORCEPROP 1 LAST BODY_TYPE PLUMBING
J 2
(100 1200);
DISPLAY 1.234043 (100 1200);
PAINT GREEN (100 1200);
DISPLAY INVISIBLE (100 1200);
FORCEPROP 1 LAST HDL_TAP TRUE
J 2
(-225 1125);
DISPLAY 1.234043 (-225 1125);
PAINT GREEN (-225 1125);
DISPLAY INVISIBLE (-225 1125);
FORCEPROP 1 LAST PATH I61
J 2
(102 1250);
DISPLAY 0.872340 (102 1250);
PAINT GREEN (102 1250);
DISPLAY INVISIBLE (102 1250);
FORCEADD TAP..6
R 2
(100 1350);
FORCEPROP 3 LASTPIN (50 1350) SIG_NAME M_A_DQ<3>
J 0
(60 1360);
DISPLAY 0.659574 (60 1360);
PAINT MONO (60 1360);
DISPLAY INVISIBLE (60 1360);
FORCEPROP 1 LASTPIN (50 1350) BN 3
J 2
(100 1360);
DISPLAY 0.617021 (100 1360);
PAINT PINK (100 1360);
FORCEPROP 2 LAST CDS_LIB mstr_standard
J 2
(100 1350);
DISPLAY 0.787234 (100 1350);
PAINT MONO (100 1350);
DISPLAY INVISIBLE (100 1350);
FORCEPROP 1 LAST BODY_TYPE PLUMBING
J 2
(100 1300);
DISPLAY 1.234043 (100 1300);
PAINT GREEN (100 1300);
DISPLAY INVISIBLE (100 1300);
FORCEPROP 1 LAST HDL_TAP TRUE
J 2
(-225 1225);
DISPLAY 1.234043 (-225 1225);
PAINT GREEN (-225 1225);
DISPLAY INVISIBLE (-225 1225);
FORCEPROP 1 LAST PATH I62
J 2
(102 1350);
DISPLAY 0.872340 (102 1350);
PAINT GREEN (102 1350);
DISPLAY INVISIBLE (102 1350);
FORCEADD TAP..6
R 2
(100 1450);
FORCEPROP 3 LASTPIN (50 1450) SIG_NAME M_A_DQ<5>
J 0
(60 1460);
DISPLAY 0.659574 (60 1460);
PAINT MONO (60 1460);
DISPLAY INVISIBLE (60 1460);
FORCEPROP 1 LASTPIN (50 1450) BN 5
J 2
(100 1460);
DISPLAY 0.617021 (100 1460);
PAINT PINK (100 1460);
FORCEPROP 2 LAST CDS_LIB mstr_standard
J 2
(100 1450);
DISPLAY 0.787234 (100 1450);
PAINT MONO (100 1450);
DISPLAY INVISIBLE (100 1450);
FORCEPROP 1 LAST BODY_TYPE PLUMBING
J 2
(100 1400);
DISPLAY 1.234043 (100 1400);
PAINT GREEN (100 1400);
DISPLAY INVISIBLE (100 1400);
FORCEPROP 1 LAST HDL_TAP TRUE
J 2
(-225 1325);
DISPLAY 1.234043 (-225 1325);
PAINT GREEN (-225 1325);
DISPLAY INVISIBLE (-225 1325);
FORCEPROP 1 LAST PATH I63
J 2
(102 1450);
DISPLAY 0.872340 (102 1450);
PAINT GREEN (102 1450);
DISPLAY INVISIBLE (102 1450);
FORCEADD TAP..6
R 2
(100 1400);
FORCEPROP 3 LASTPIN (50 1400) SIG_NAME M_A_DQ<4>
J 0
(60 1410);
DISPLAY 0.659574 (60 1410);
PAINT MONO (60 1410);
DISPLAY INVISIBLE (60 1410);
FORCEPROP 1 LASTPIN (50 1400) BN 4
J 2
(100 1410);
DISPLAY 0.617021 (100 1410);
PAINT PINK (100 1410);
FORCEPROP 2 LAST CDS_LIB mstr_standard
J 2
(100 1400);
DISPLAY 0.787234 (100 1400);
PAINT MONO (100 1400);
DISPLAY INVISIBLE (100 1400);
FORCEPROP 1 LAST BODY_TYPE PLUMBING
J 2
(100 1350);
DISPLAY 1.234043 (100 1350);
PAINT GREEN (100 1350);
DISPLAY INVISIBLE (100 1350);
FORCEPROP 1 LAST HDL_TAP TRUE
J 2
(-225 1275);
DISPLAY 1.234043 (-225 1275);
PAINT GREEN (-225 1275);
DISPLAY INVISIBLE (-225 1275);
FORCEPROP 1 LAST PATH I64
J 2
(102 1400);
DISPLAY 0.872340 (102 1400);
PAINT GREEN (102 1400);
DISPLAY INVISIBLE (102 1400);
FORCEADD TAP..6
R 2
(100 1600);
FORCEPROP 3 LASTPIN (50 1600) SIG_NAME M_A_DQ<8>
J 0
(60 1610);
DISPLAY 0.659574 (60 1610);
PAINT MONO (60 1610);
DISPLAY INVISIBLE (60 1610);
FORCEPROP 1 LASTPIN (50 1600) BN 8
J 2
(100 1610);
DISPLAY 0.617021 (100 1610);
PAINT PINK (100 1610);
FORCEPROP 2 LAST CDS_LIB mstr_standard
J 2
(100 1600);
DISPLAY 0.787234 (100 1600);
PAINT MONO (100 1600);
DISPLAY INVISIBLE (100 1600);
FORCEPROP 1 LAST BODY_TYPE PLUMBING
J 2
(100 1550);
DISPLAY 1.234043 (100 1550);
PAINT GREEN (100 1550);
DISPLAY INVISIBLE (100 1550);
FORCEPROP 1 LAST HDL_TAP TRUE
J 2
(-225 1475);
DISPLAY 1.234043 (-225 1475);
PAINT GREEN (-225 1475);
DISPLAY INVISIBLE (-225 1475);
FORCEPROP 1 LAST PATH I65
J 2
(102 1600);
DISPLAY 0.872340 (102 1600);
PAINT GREEN (102 1600);
DISPLAY INVISIBLE (102 1600);
FORCEADD TAP..6
R 2
(100 1550);
FORCEPROP 3 LASTPIN (50 1550) SIG_NAME M_A_DQ<7>
J 0
(60 1560);
DISPLAY 0.659574 (60 1560);
PAINT MONO (60 1560);
DISPLAY INVISIBLE (60 1560);
FORCEPROP 1 LASTPIN (50 1550) BN 7
J 2
(100 1560);
DISPLAY 0.617021 (100 1560);
PAINT PINK (100 1560);
FORCEPROP 2 LAST CDS_LIB mstr_standard
J 2
(100 1550);
DISPLAY 0.787234 (100 1550);
PAINT MONO (100 1550);
DISPLAY INVISIBLE (100 1550);
FORCEPROP 1 LAST BODY_TYPE PLUMBING
J 2
(100 1500);
DISPLAY 1.234043 (100 1500);
PAINT GREEN (100 1500);
DISPLAY INVISIBLE (100 1500);
FORCEPROP 1 LAST HDL_TAP TRUE
J 2
(-225 1425);
DISPLAY 1.234043 (-225 1425);
PAINT GREEN (-225 1425);
DISPLAY INVISIBLE (-225 1425);
FORCEPROP 1 LAST PATH I66
J 2
(102 1550);
DISPLAY 0.872340 (102 1550);
PAINT GREEN (102 1550);
DISPLAY INVISIBLE (102 1550);
FORCEADD TAP..6
R 2
(100 1500);
FORCEPROP 3 LASTPIN (50 1500) SIG_NAME M_A_DQ<6>
J 0
(60 1510);
DISPLAY 0.659574 (60 1510);
PAINT MONO (60 1510);
DISPLAY INVISIBLE (60 1510);
FORCEPROP 1 LASTPIN (50 1500) BN 6
J 2
(100 1510);
DISPLAY 0.617021 (100 1510);
PAINT PINK (100 1510);
FORCEPROP 2 LAST CDS_LIB mstr_standard
J 2
(100 1500);
DISPLAY 0.787234 (100 1500);
PAINT MONO (100 1500);
DISPLAY INVISIBLE (100 1500);
FORCEPROP 1 LAST BODY_TYPE PLUMBING
J 2
(100 1450);
DISPLAY 1.234043 (100 1450);
PAINT GREEN (100 1450);
DISPLAY INVISIBLE (100 1450);
FORCEPROP 1 LAST HDL_TAP TRUE
J 2
(-225 1375);
DISPLAY 1.234043 (-225 1375);
PAINT GREEN (-225 1375);
DISPLAY INVISIBLE (-225 1375);
FORCEPROP 1 LAST PATH I67
J 2
(102 1500);
DISPLAY 0.872340 (102 1500);
PAINT GREEN (102 1500);
DISPLAY INVISIBLE (102 1500);
FORCEADD TAP..6
R 2
(100 1650);
FORCEPROP 3 LASTPIN (50 1650) SIG_NAME M_A_DQ<9>
J 0
(60 1660);
DISPLAY 0.659574 (60 1660);
PAINT MONO (60 1660);
DISPLAY INVISIBLE (60 1660);
FORCEPROP 1 LASTPIN (50 1650) BN 9
J 2
(100 1660);
DISPLAY 0.617021 (100 1660);
PAINT PINK (100 1660);
FORCEPROP 2 LAST CDS_LIB mstr_standard
J 2
(100 1650);
DISPLAY 0.787234 (100 1650);
PAINT MONO (100 1650);
DISPLAY INVISIBLE (100 1650);
FORCEPROP 1 LAST BODY_TYPE PLUMBING
J 2
(100 1600);
DISPLAY 1.234043 (100 1600);
PAINT GREEN (100 1600);
DISPLAY INVISIBLE (100 1600);
FORCEPROP 1 LAST HDL_TAP TRUE
J 2
(-225 1525);
DISPLAY 1.234043 (-225 1525);
PAINT GREEN (-225 1525);
DISPLAY INVISIBLE (-225 1525);
FORCEPROP 1 LAST PATH I68
J 2
(102 1650);
DISPLAY 0.872340 (102 1650);
PAINT GREEN (102 1650);
DISPLAY INVISIBLE (102 1650);
FORCEADD TAP..6
R 2
(100 1700);
FORCEPROP 3 LASTPIN (50 1700) SIG_NAME M_A_DQ<10>
J 0
(60 1710);
DISPLAY 0.659574 (60 1710);
PAINT MONO (60 1710);
DISPLAY INVISIBLE (60 1710);
FORCEPROP 1 LASTPIN (50 1700) BN 10
J 2
(100 1710);
DISPLAY 0.617021 (100 1710);
PAINT PINK (100 1710);
FORCEPROP 2 LAST CDS_LIB mstr_standard
J 2
(100 1700);
DISPLAY 0.787234 (100 1700);
PAINT MONO (100 1700);
DISPLAY INVISIBLE (100 1700);
FORCEPROP 1 LAST BODY_TYPE PLUMBING
J 2
(100 1650);
DISPLAY 1.234043 (100 1650);
PAINT GREEN (100 1650);
DISPLAY INVISIBLE (100 1650);
FORCEPROP 1 LAST HDL_TAP TRUE
J 2
(-225 1575);
DISPLAY 1.234043 (-225 1575);
PAINT GREEN (-225 1575);
DISPLAY INVISIBLE (-225 1575);
FORCEPROP 1 LAST PATH I69
J 2
(102 1700);
DISPLAY 0.872340 (102 1700);
PAINT GREEN (102 1700);
DISPLAY INVISIBLE (102 1700);
FORCEADD OFFPAGE..5
(-2325 1700);
FORCEPROP 2 LAST $XR1 23 
J 0
(-2669 1700);
DISPLAY 0.638298 (-2669 1700);
PAINT MONO (-2669 1700);
FORCEPROP 2 LAST $XR0 43 
J 0
(-2579 1700);
DISPLAY 0.638298 (-2579 1700);
PAINT MONO (-2579 1700);
FORCEPROP 2 LAST CDS_LIB mstr_standard
J 0
(-2325 1700);
DISPLAY 0.787234 (-2325 1700);
PAINT MONO (-2325 1700);
DISPLAY INVISIBLE (-2325 1700);
FORCEPROP 1 LAST OFFPAGE TRUE
J 0
(-2000 1575);
DISPLAY 1.404255 (-2000 1575);
PAINT GREEN (-2000 1575);
DISPLAY INVISIBLE (-2000 1575);
FORCEPROP 1 LAST COMMENT_BODY TRUE
J 0
(-2225 1625);
DISPLAY 1.404255 (-2225 1625);
PAINT GREEN (-2225 1625);
DISPLAY INVISIBLE (-2225 1625);
FORCEPROP 2 LAST PATH I7
J 0
(-2575 1750);
DISPLAY 1.021277 (-2575 1750);
PAINT ORANGE (-2575 1750);
DISPLAY INVISIBLE (-2575 1750);
FORCEADD TAP..6
R 2
(100 1800);
FORCEPROP 3 LASTPIN (50 1800) SIG_NAME M_A_DQ<12>
J 0
(60 1810);
DISPLAY 0.659574 (60 1810);
PAINT MONO (60 1810);
DISPLAY INVISIBLE (60 1810);
FORCEPROP 1 LASTPIN (50 1800) BN 12
J 2
(100 1810);
DISPLAY 0.617021 (100 1810);
PAINT PINK (100 1810);
FORCEPROP 2 LAST CDS_LIB mstr_standard
J 2
(100 1800);
DISPLAY 0.787234 (100 1800);
PAINT MONO (100 1800);
DISPLAY INVISIBLE (100 1800);
FORCEPROP 1 LAST BODY_TYPE PLUMBING
J 2
(100 1750);
DISPLAY 1.234043 (100 1750);
PAINT GREEN (100 1750);
DISPLAY INVISIBLE (100 1750);
FORCEPROP 1 LAST HDL_TAP TRUE
J 2
(-225 1675);
DISPLAY 1.234043 (-225 1675);
PAINT GREEN (-225 1675);
DISPLAY INVISIBLE (-225 1675);
FORCEPROP 1 LAST PATH I70
J 2
(102 1800);
DISPLAY 0.872340 (102 1800);
PAINT GREEN (102 1800);
DISPLAY INVISIBLE (102 1800);
FORCEADD TAP..6
R 2
(100 1750);
FORCEPROP 3 LASTPIN (50 1750) SIG_NAME M_A_DQ<11>
J 0
(60 1760);
DISPLAY 0.659574 (60 1760);
PAINT MONO (60 1760);
DISPLAY INVISIBLE (60 1760);
FORCEPROP 1 LASTPIN (50 1750) BN 11
J 2
(100 1760);
DISPLAY 0.617021 (100 1760);
PAINT PINK (100 1760);
FORCEPROP 2 LAST CDS_LIB mstr_standard
J 2
(100 1750);
DISPLAY 0.787234 (100 1750);
PAINT MONO (100 1750);
DISPLAY INVISIBLE (100 1750);
FORCEPROP 1 LAST BODY_TYPE PLUMBING
J 2
(100 1700);
DISPLAY 1.234043 (100 1700);
PAINT GREEN (100 1700);
DISPLAY INVISIBLE (100 1700);
FORCEPROP 1 LAST HDL_TAP TRUE
J 2
(-225 1625);
DISPLAY 1.234043 (-225 1625);
PAINT GREEN (-225 1625);
DISPLAY INVISIBLE (-225 1625);
FORCEPROP 1 LAST PATH I71
J 2
(102 1750);
DISPLAY 0.872340 (102 1750);
PAINT GREEN (102 1750);
DISPLAY INVISIBLE (102 1750);
FORCEADD TAP..6
R 2
(100 1850);
FORCEPROP 3 LASTPIN (50 1850) SIG_NAME M_A_DQ<13>
J 0
(60 1860);
DISPLAY 0.659574 (60 1860);
PAINT MONO (60 1860);
DISPLAY INVISIBLE (60 1860);
FORCEPROP 1 LASTPIN (50 1850) BN 13
J 2
(100 1860);
DISPLAY 0.617021 (100 1860);
PAINT PINK (100 1860);
FORCEPROP 2 LAST CDS_LIB mstr_standard
J 2
(100 1850);
DISPLAY 0.787234 (100 1850);
PAINT MONO (100 1850);
DISPLAY INVISIBLE (100 1850);
FORCEPROP 1 LAST BODY_TYPE PLUMBING
J 2
(100 1800);
DISPLAY 1.234043 (100 1800);
PAINT GREEN (100 1800);
DISPLAY INVISIBLE (100 1800);
FORCEPROP 1 LAST HDL_TAP TRUE
J 2
(-225 1725);
DISPLAY 1.234043 (-225 1725);
PAINT GREEN (-225 1725);
DISPLAY INVISIBLE (-225 1725);
FORCEPROP 1 LAST PATH I72
J 2
(102 1850);
DISPLAY 0.872340 (102 1850);
PAINT GREEN (102 1850);
DISPLAY INVISIBLE (102 1850);
FORCEADD TAP..6
R 2
(100 1950);
FORCEPROP 3 LASTPIN (50 1950) SIG_NAME M_A_DQ<15>
J 0
(60 1960);
DISPLAY 0.659574 (60 1960);
PAINT MONO (60 1960);
DISPLAY INVISIBLE (60 1960);
FORCEPROP 1 LASTPIN (50 1950) BN 15
J 2
(100 1960);
DISPLAY 0.617021 (100 1960);
PAINT PINK (100 1960);
FORCEPROP 2 LAST CDS_LIB mstr_standard
J 2
(100 1950);
DISPLAY 0.787234 (100 1950);
PAINT MONO (100 1950);
DISPLAY INVISIBLE (100 1950);
FORCEPROP 1 LAST BODY_TYPE PLUMBING
J 2
(100 1900);
DISPLAY 1.234043 (100 1900);
PAINT GREEN (100 1900);
DISPLAY INVISIBLE (100 1900);
FORCEPROP 1 LAST HDL_TAP TRUE
J 2
(-225 1825);
DISPLAY 1.234043 (-225 1825);
PAINT GREEN (-225 1825);
DISPLAY INVISIBLE (-225 1825);
FORCEPROP 1 LAST PATH I73
J 2
(102 1950);
DISPLAY 0.872340 (102 1950);
PAINT GREEN (102 1950);
DISPLAY INVISIBLE (102 1950);
FORCEADD TAP..6
R 2
(100 1900);
FORCEPROP 3 LASTPIN (50 1900) SIG_NAME M_A_DQ<14>
J 0
(60 1910);
DISPLAY 0.659574 (60 1910);
PAINT MONO (60 1910);
DISPLAY INVISIBLE (60 1910);
FORCEPROP 1 LASTPIN (50 1900) BN 14
J 2
(100 1910);
DISPLAY 0.617021 (100 1910);
PAINT PINK (100 1910);
FORCEPROP 2 LAST CDS_LIB mstr_standard
J 2
(100 1900);
DISPLAY 0.787234 (100 1900);
PAINT MONO (100 1900);
DISPLAY INVISIBLE (100 1900);
FORCEPROP 1 LAST BODY_TYPE PLUMBING
J 2
(100 1850);
DISPLAY 1.234043 (100 1850);
PAINT GREEN (100 1850);
DISPLAY INVISIBLE (100 1850);
FORCEPROP 1 LAST HDL_TAP TRUE
J 2
(-225 1775);
DISPLAY 1.234043 (-225 1775);
PAINT GREEN (-225 1775);
DISPLAY INVISIBLE (-225 1775);
FORCEPROP 1 LAST PATH I74
J 2
(102 1900);
DISPLAY 0.872340 (102 1900);
PAINT GREEN (102 1900);
DISPLAY INVISIBLE (102 1900);
FORCEADD SCONN288_H44441003..4
(1600 1650);
FORCEPROP 1 LAST LOCATION J6T1
J 0
(1150 2750);
DISPLAY 0.617021 (1150 2750);
PAINT AQUA (1150 2750);
FORCEPROP 1 LAST MATERIAL SCONN
J 0
(1150 2700);
DISPLAY 0.617021 (1150 2700);
PAINT SKYBLUE (1150 2700);
FORCEPROP 2 LASTPIN (1100 2200) $PN 77
J 2
(1090 2210);
DISPLAY 0.617021 (1090 2210);
PAINT ORANGE (1090 2210);
FORCEPROP 2 LASTPIN (1100 2150) $PN 221
J 2
(1090 2160);
DISPLAY 0.617021 (1090 2160);
PAINT ORANGE (1090 2160);
FORCEPROP 2 LASTPIN (1100 2500) $PN 142
J 2
(1090 2510);
DISPLAY 0.617021 (1090 2510);
PAINT ORANGE (1090 2510);
FORCEPROP 2 LASTPIN (1100 2450) $PN 143
J 2
(1090 2460);
DISPLAY 0.617021 (1090 2460);
PAINT ORANGE (1090 2460);
FORCEPROP 2 LASTPIN (1100 2400) $PN 288
J 2
(1090 2410);
DISPLAY 0.617021 (1090 2410);
PAINT ORANGE (1090 2410);
FORCEPROP 2 LASTPIN (1100 2350) $PN 286
J 2
(1090 2360);
DISPLAY 0.617021 (1090 2360);
PAINT ORANGE (1090 2360);
FORCEPROP 2 LASTPIN (1100 2300) $PN 287
J 2
(1090 2310);
DISPLAY 0.617021 (1090 2310);
PAINT ORANGE (1090 2310);
FORCEPROP 2 LASTPIN (1100 2050) $PN 59
J 2
(1090 2060);
DISPLAY 0.617021 (1090 2060);
PAINT ORANGE (1090 2060);
FORCEPROP 2 LASTPIN (1100 2000) $PN 61
J 2
(1090 2010);
DISPLAY 0.617021 (1090 2010);
PAINT ORANGE (1090 2010);
FORCEPROP 2 LASTPIN (1100 1950) $PN 64
J 2
(1090 1960);
DISPLAY 0.617021 (1090 1960);
PAINT ORANGE (1090 1960);
FORCEPROP 2 LASTPIN (1100 1900) $PN 67
J 2
(1090 1910);
DISPLAY 0.617021 (1090 1910);
PAINT ORANGE (1090 1910);
FORCEPROP 2 LASTPIN (1100 1850) $PN 70
J 2
(1090 1860);
DISPLAY 0.617021 (1090 1860);
PAINT ORANGE (1090 1860);
FORCEPROP 2 LASTPIN (1100 1800) $PN 73
J 2
(1090 1810);
DISPLAY 0.617021 (1090 1810);
PAINT ORANGE (1090 1810);
FORCEPROP 2 LASTPIN (1100 1750) $PN 76
J 2
(1090 1760);
DISPLAY 0.617021 (1090 1760);
PAINT ORANGE (1090 1760);
FORCEPROP 2 LASTPIN (1100 1700) $PN 80
J 2
(1090 1710);
DISPLAY 0.617021 (1090 1710);
PAINT ORANGE (1090 1710);
FORCEPROP 2 LASTPIN (1100 1650) $PN 83
J 2
(1090 1660);
DISPLAY 0.617021 (1090 1660);
PAINT ORANGE (1090 1660);
FORCEPROP 2 LASTPIN (1100 1600) $PN 85
J 2
(1090 1610);
DISPLAY 0.617021 (1090 1610);
PAINT ORANGE (1090 1610);
FORCEPROP 2 LASTPIN (1100 1550) $PN 88
J 2
(1090 1560);
DISPLAY 0.617021 (1090 1560);
PAINT ORANGE (1090 1560);
FORCEPROP 2 LASTPIN (1100 1500) $PN 90
J 2
(1090 1510);
DISPLAY 0.617021 (1090 1510);
PAINT ORANGE (1090 1510);
FORCEPROP 2 LASTPIN (1100 1400) $PN 204
J 2
(1090 1410);
DISPLAY 0.617021 (1090 1410);
PAINT ORANGE (1090 1410);
FORCEPROP 2 LASTPIN (1100 1350) $PN 206
J 2
(1090 1360);
DISPLAY 0.617021 (1090 1360);
PAINT ORANGE (1090 1360);
FORCEPROP 2 LASTPIN (1100 1300) $PN 209
J 2
(1090 1310);
DISPLAY 0.617021 (1090 1310);
PAINT ORANGE (1090 1310);
FORCEPROP 2 LASTPIN (1100 1250) $PN 212
J 2
(1090 1260);
DISPLAY 0.617021 (1090 1260);
PAINT ORANGE (1090 1260);
FORCEPROP 2 LASTPIN (1100 1200) $PN 215
J 2
(1090 1210);
DISPLAY 0.617021 (1090 1210);
PAINT ORANGE (1090 1210);
FORCEPROP 2 LASTPIN (1100 1150) $PN 217
J 2
(1090 1160);
DISPLAY 0.617021 (1090 1160);
PAINT ORANGE (1090 1160);
FORCEPROP 2 LASTPIN (1100 1100) $PN 220
J 2
(1090 1110);
DISPLAY 0.617021 (1090 1110);
PAINT ORANGE (1090 1110);
FORCEPROP 2 LASTPIN (1100 1050) $PN 223
J 2
(1090 1060);
DISPLAY 0.617021 (1090 1060);
PAINT ORANGE (1090 1060);
FORCEPROP 2 LASTPIN (1100 1000) $PN 226
J 2
(1090 1010);
DISPLAY 0.617021 (1090 1010);
PAINT ORANGE (1090 1010);
FORCEPROP 2 LASTPIN (1100 950) $PN 229
J 2
(1090 960);
DISPLAY 0.617021 (1090 960);
PAINT ORANGE (1090 960);
FORCEPROP 2 LASTPIN (1100 850) $PN 233
J 2
(1090 860);
DISPLAY 0.617021 (1090 860);
PAINT ORANGE (1090 860);
FORCEPROP 2 LASTPIN (1100 800) $PN 236
J 2
(1090 810);
DISPLAY 0.617021 (1090 810);
PAINT ORANGE (1090 810);
FORCEPROP 2 LASTPIN (2100 2500) $PN 1
J 0
(2110 2510);
DISPLAY 0.617021 (2110 2510);
PAINT ORANGE (2110 2510);
FORCEPROP 2 LASTPIN (2100 2450) $PN 145
J 0
(2110 2460);
DISPLAY 0.617021 (2110 2460);
PAINT ORANGE (2110 2460);
FORCEPROP 2 LASTPIN (1100 1450) $PN 92
J 2
(1090 1460);
DISPLAY 0.617021 (1090 1460);
PAINT ORANGE (1090 1460);
FORCEPROP 1 LAST PART_NUMBER H44441-003
J 0
(1150 600);
DISPLAY 0.617021 (1150 600);
PAINT BLUE (1150 600);
FORCEPROP 2 LASTPIN (1100 900) $PN 231
J 2
(1090 910);
DISPLAY 0.617021 (1090 910);
PAINT ORANGE (1090 910);
FORCEPROP 0 LAST BOM_SS NOPOP
J 0
(1365 2731);
DISPLAY 1.021277 (1365 2731);
PAINT BROWN (1365 2731);
DISPLAY BOTH (1365 2731);
FORCEPROP 1 LAST PACK_TYPE PIP
J 0
(1150 2800);
PAINT SKYBLUE (1150 2800);
DISPLAY INVISIBLE (1150 2800);
FORCEPROP 2 LAST BOM_COST MEM
J 0
(1600 1650);
PAINT ORANGE (1600 1650);
DISPLAY INVISIBLE (1600 1650);
FORCEPROP 2 LAST CDS_LIB mstr_sconn
J 0
(1600 1650);
PAINT ORANGE (1600 1650);
DISPLAY INVISIBLE (1600 1650);
FORCEPROP 2 LAST SEC_TYPE PIP
J 0
(1150 2800);
DISPLAY 1.021277 (1150 2800);
PAINT ORANGE (1150 2800);
DISPLAY INVISIBLE (1150 2800);
FORCEPROP 2 LAST SEC 4
J 0
(1150 2800);
DISPLAY 0.680851 (1150 2800);
PAINT MONO (1150 2800);
DISPLAY INVISIBLE (1150 2800);
FORCEPROP 2 LAST CDS_LOCATION J6T1
J 0
(1150 2750);
DISPLAY 0.617021 (1150 2750);
PAINT AQUA (1150 2750);
DISPLAY INVISIBLE (1150 2750);
FORCEPROP 1 LAST PATH I75
J 0
(1600 2700);
PAINT GREEN (1600 2700);
DISPLAY INVISIBLE (1600 2700);
FORCEPROP 2 LAST ROOM DDR4_CH_A
J 0
(1600 1650);
PAINT ORANGE (1600 1650);
DISPLAY INVISIBLE (1600 1650);
FORCEADD TAP..6
R 2
(100 2000);
FORCEPROP 3 LASTPIN (50 2000) SIG_NAME M_A_DQ<16>
J 0
(60 2010);
DISPLAY 0.659574 (60 2010);
PAINT MONO (60 2010);
DISPLAY INVISIBLE (60 2010);
FORCEPROP 1 LASTPIN (50 2000) BN 16
J 2
(100 2010);
DISPLAY 0.617021 (100 2010);
PAINT PINK (100 2010);
FORCEPROP 2 LAST CDS_LIB mstr_standard
J 2
(100 2000);
DISPLAY 0.787234 (100 2000);
PAINT MONO (100 2000);
DISPLAY INVISIBLE (100 2000);
FORCEPROP 1 LAST BODY_TYPE PLUMBING
J 2
(100 1950);
DISPLAY 1.234043 (100 1950);
PAINT GREEN (100 1950);
DISPLAY INVISIBLE (100 1950);
FORCEPROP 1 LAST HDL_TAP TRUE
J 2
(-225 1875);
DISPLAY 1.234043 (-225 1875);
PAINT GREEN (-225 1875);
DISPLAY INVISIBLE (-225 1875);
FORCEPROP 1 LAST PATH I76
J 2
(102 2000);
DISPLAY 0.872340 (102 2000);
PAINT GREEN (102 2000);
DISPLAY INVISIBLE (102 2000);
FORCEADD TAP..6
R 2
(100 2050);
FORCEPROP 3 LASTPIN (50 2050) SIG_NAME M_A_DQ<17>
J 0
(60 2060);
DISPLAY 0.659574 (60 2060);
PAINT MONO (60 2060);
DISPLAY INVISIBLE (60 2060);
FORCEPROP 1 LASTPIN (50 2050) BN 17
J 2
(100 2060);
DISPLAY 0.617021 (100 2060);
PAINT PINK (100 2060);
FORCEPROP 2 LAST CDS_LIB mstr_standard
J 2
(100 2050);
DISPLAY 0.787234 (100 2050);
PAINT MONO (100 2050);
DISPLAY INVISIBLE (100 2050);
FORCEPROP 1 LAST BODY_TYPE PLUMBING
J 2
(100 2000);
DISPLAY 1.234043 (100 2000);
PAINT GREEN (100 2000);
DISPLAY INVISIBLE (100 2000);
FORCEPROP 1 LAST HDL_TAP TRUE
J 2
(-225 1925);
DISPLAY 1.234043 (-225 1925);
PAINT GREEN (-225 1925);
DISPLAY INVISIBLE (-225 1925);
FORCEPROP 1 LAST PATH I77
J 2
(102 2050);
DISPLAY 0.872340 (102 2050);
PAINT GREEN (102 2050);
DISPLAY INVISIBLE (102 2050);
FORCEADD TAP..6
R 2
(100 2100);
FORCEPROP 3 LASTPIN (50 2100) SIG_NAME M_A_DQ<18>
J 0
(60 2110);
DISPLAY 0.659574 (60 2110);
PAINT MONO (60 2110);
DISPLAY INVISIBLE (60 2110);
FORCEPROP 1 LASTPIN (50 2100) BN 18
J 2
(100 2110);
DISPLAY 0.617021 (100 2110);
PAINT PINK (100 2110);
FORCEPROP 2 LAST CDS_LIB mstr_standard
J 2
(100 2100);
DISPLAY 0.787234 (100 2100);
PAINT MONO (100 2100);
DISPLAY INVISIBLE (100 2100);
FORCEPROP 1 LAST BODY_TYPE PLUMBING
J 2
(100 2050);
DISPLAY 1.234043 (100 2050);
PAINT GREEN (100 2050);
DISPLAY INVISIBLE (100 2050);
FORCEPROP 1 LAST HDL_TAP TRUE
J 2
(-225 1975);
DISPLAY 1.234043 (-225 1975);
PAINT GREEN (-225 1975);
DISPLAY INVISIBLE (-225 1975);
FORCEPROP 1 LAST PATH I78
J 2
(102 2100);
DISPLAY 0.872340 (102 2100);
PAINT GREEN (102 2100);
DISPLAY INVISIBLE (102 2100);
FORCEADD TAP..6
R 2
(100 2150);
FORCEPROP 3 LASTPIN (50 2150) SIG_NAME M_A_DQ<19>
J 0
(60 2160);
DISPLAY 0.659574 (60 2160);
PAINT MONO (60 2160);
DISPLAY INVISIBLE (60 2160);
FORCEPROP 1 LASTPIN (50 2150) BN 19
J 2
(100 2160);
DISPLAY 0.617021 (100 2160);
PAINT PINK (100 2160);
FORCEPROP 2 LAST CDS_LIB mstr_standard
J 2
(100 2150);
DISPLAY 0.787234 (100 2150);
PAINT MONO (100 2150);
DISPLAY INVISIBLE (100 2150);
FORCEPROP 1 LAST BODY_TYPE PLUMBING
J 2
(100 2100);
DISPLAY 1.234043 (100 2100);
PAINT GREEN (100 2100);
DISPLAY INVISIBLE (100 2100);
FORCEPROP 1 LAST HDL_TAP TRUE
J 2
(-225 2025);
DISPLAY 1.234043 (-225 2025);
PAINT GREEN (-225 2025);
DISPLAY INVISIBLE (-225 2025);
FORCEPROP 1 LAST PATH I79
J 2
(102 2150);
DISPLAY 0.872340 (102 2150);
PAINT GREEN (102 2150);
DISPLAY INVISIBLE (102 2150);
FORCEADD OFFPAGE..5
(-2425 2000);
FORCEPROP 2 LAST $XR23 94 
J 0
(-2919 2036);
DISPLAY 0.638298 (-2919 2036);
PAINT MONO (-2919 2036);
FORCEPROP 2 LAST $XR22 88 
J 0
(-2829 2036);
DISPLAY 0.638298 (-2829 2036);
PAINT MONO (-2829 2036);
FORCEPROP 2 LAST $XR21 87 
J 0
(-2739 2036);
DISPLAY 0.638298 (-2739 2036);
PAINT MONO (-2739 2036);
FORCEPROP 2 LAST $XR20 86 
J 0
(-2649 2036);
DISPLAY 0.638298 (-2649 2036);
PAINT MONO (-2649 2036);
FORCEPROP 2 LAST $XR19 85 
J 0
(-3459 1964);
DISPLAY 0.638298 (-3459 1964);
PAINT MONO (-3459 1964);
FORCEPROP 2 LAST $XR18 84 
J 0
(-3369 1964);
DISPLAY 0.638298 (-3369 1964);
PAINT MONO (-3369 1964);
FORCEPROP 2 LAST $XR17 83 
J 0
(-3279 1964);
DISPLAY 0.638298 (-3279 1964);
PAINT MONO (-3279 1964);
FORCEPROP 2 LAST $XR16 82 
J 0
(-3189 1964);
DISPLAY 0.638298 (-3189 1964);
PAINT MONO (-3189 1964);
FORCEPROP 2 LAST $XR15 81 
J 0
(-3099 1964);
DISPLAY 0.638298 (-3099 1964);
PAINT MONO (-3099 1964);
FORCEPROP 2 LAST $XR14 80 
J 0
(-3009 1964);
DISPLAY 0.638298 (-3009 1964);
PAINT MONO (-3009 1964);
FORCEPROP 2 LAST $XR13 79 
J 0
(-2919 1964);
DISPLAY 0.638298 (-2919 1964);
PAINT MONO (-2919 1964);
FORCEPROP 2 LAST $XR12 78 
J 0
(-2829 1964);
DISPLAY 0.638298 (-2829 1964);
PAINT MONO (-2829 1964);
FORCEPROP 2 LAST $XR11 77 
J 0
(-2739 1964);
DISPLAY 0.638298 (-2739 1964);
PAINT MONO (-2739 1964);
FORCEPROP 2 LAST $XR10 54 
J 0
(-2649 1964);
DISPLAY 0.638298 (-2649 1964);
PAINT MONO (-2649 1964);
FORCEPROP 2 LAST $XR9 53 
J 0
(-3459 2000);
DISPLAY 0.638298 (-3459 2000);
PAINT MONO (-3459 2000);
FORCEPROP 2 LAST $XR8 52 
J 0
(-3369 2000);
DISPLAY 0.638298 (-3369 2000);
PAINT MONO (-3369 2000);
FORCEPROP 2 LAST $XR7 51 
J 0
(-3279 2000);
DISPLAY 0.638298 (-3279 2000);
PAINT MONO (-3279 2000);
FORCEPROP 2 LAST $XR6 50 
J 0
(-3189 2000);
DISPLAY 0.638298 (-3189 2000);
PAINT MONO (-3189 2000);
FORCEPROP 2 LAST $XR5 49 
J 0
(-3099 2000);
DISPLAY 0.638298 (-3099 2000);
PAINT MONO (-3099 2000);
FORCEPROP 2 LAST $XR4 48 
J 0
(-3009 2000);
DISPLAY 0.638298 (-3009 2000);
PAINT MONO (-3009 2000);
FORCEPROP 2 LAST $XR3 47 
J 0
(-2919 2000);
DISPLAY 0.638298 (-2919 2000);
PAINT MONO (-2919 2000);
FORCEPROP 2 LAST $XR2 46 
J 0
(-2829 2000);
DISPLAY 0.638298 (-2829 2000);
PAINT MONO (-2829 2000);
FORCEPROP 2 LAST $XR1 45 
J 0
(-2739 2000);
DISPLAY 0.638298 (-2739 2000);
PAINT MONO (-2739 2000);
FORCEPROP 2 LAST $XR0 43 
J 0
(-2649 2000);
DISPLAY 0.638298 (-2649 2000);
PAINT MONO (-2649 2000);
FORCEPROP 2 LAST CDS_LIB mstr_standard
J 0
(-2425 2000);
DISPLAY 0.787234 (-2425 2000);
PAINT MONO (-2425 2000);
DISPLAY INVISIBLE (-2425 2000);
FORCEPROP 1 LAST OFFPAGE TRUE
J 0
(-2100 1875);
DISPLAY 1.404255 (-2100 1875);
PAINT GREEN (-2100 1875);
DISPLAY INVISIBLE (-2100 1875);
FORCEPROP 1 LAST COMMENT_BODY TRUE
J 0
(-2325 1925);
DISPLAY 1.404255 (-2325 1925);
PAINT GREEN (-2325 1925);
DISPLAY INVISIBLE (-2325 1925);
FORCEPROP 2 LAST PATH I8
J 0
(-2625 2050);
DISPLAY 1.021277 (-2625 2050);
PAINT ORANGE (-2625 2050);
DISPLAY INVISIBLE (-2625 2050);
FORCEADD TAP..6
R 2
(100 2250);
FORCEPROP 3 LASTPIN (50 2250) SIG_NAME M_A_DQ<21>
J 0
(60 2260);
DISPLAY 0.659574 (60 2260);
PAINT MONO (60 2260);
DISPLAY INVISIBLE (60 2260);
FORCEPROP 1 LASTPIN (50 2250) BN 21
J 2
(100 2260);
DISPLAY 0.617021 (100 2260);
PAINT PINK (100 2260);
FORCEPROP 2 LAST CDS_LIB mstr_standard
J 2
(100 2250);
DISPLAY 0.787234 (100 2250);
PAINT MONO (100 2250);
DISPLAY INVISIBLE (100 2250);
FORCEPROP 1 LAST BODY_TYPE PLUMBING
J 2
(100 2200);
DISPLAY 1.234043 (100 2200);
PAINT GREEN (100 2200);
DISPLAY INVISIBLE (100 2200);
FORCEPROP 1 LAST HDL_TAP TRUE
J 2
(-225 2125);
DISPLAY 1.234043 (-225 2125);
PAINT GREEN (-225 2125);
DISPLAY INVISIBLE (-225 2125);
FORCEPROP 1 LAST PATH I80
J 2
(102 2250);
DISPLAY 0.872340 (102 2250);
PAINT GREEN (102 2250);
DISPLAY INVISIBLE (102 2250);
FORCEADD TAP..6
R 2
(100 2200);
FORCEPROP 3 LASTPIN (50 2200) SIG_NAME M_A_DQ<20>
J 0
(60 2210);
DISPLAY 0.659574 (60 2210);
PAINT MONO (60 2210);
DISPLAY INVISIBLE (60 2210);
FORCEPROP 1 LASTPIN (50 2200) BN 20
J 2
(100 2210);
DISPLAY 0.617021 (100 2210);
PAINT PINK (100 2210);
FORCEPROP 2 LAST CDS_LIB mstr_standard
J 2
(100 2200);
DISPLAY 0.787234 (100 2200);
PAINT MONO (100 2200);
DISPLAY INVISIBLE (100 2200);
FORCEPROP 1 LAST BODY_TYPE PLUMBING
J 2
(100 2150);
DISPLAY 1.234043 (100 2150);
PAINT GREEN (100 2150);
DISPLAY INVISIBLE (100 2150);
FORCEPROP 1 LAST HDL_TAP TRUE
J 2
(-225 2075);
DISPLAY 1.234043 (-225 2075);
PAINT GREEN (-225 2075);
DISPLAY INVISIBLE (-225 2075);
FORCEPROP 1 LAST PATH I81
J 2
(102 2200);
DISPLAY 0.872340 (102 2200);
PAINT GREEN (102 2200);
DISPLAY INVISIBLE (102 2200);
FORCEADD TAP..6
R 2
(100 2300);
FORCEPROP 3 LASTPIN (50 2300) SIG_NAME M_A_DQ<22>
J 0
(60 2310);
DISPLAY 0.659574 (60 2310);
PAINT MONO (60 2310);
DISPLAY INVISIBLE (60 2310);
FORCEPROP 1 LASTPIN (50 2300) BN 22
J 2
(100 2310);
DISPLAY 0.617021 (100 2310);
PAINT PINK (100 2310);
FORCEPROP 2 LAST CDS_LIB mstr_standard
J 2
(100 2300);
DISPLAY 0.787234 (100 2300);
PAINT MONO (100 2300);
DISPLAY INVISIBLE (100 2300);
FORCEPROP 1 LAST BODY_TYPE PLUMBING
J 2
(100 2250);
DISPLAY 1.234043 (100 2250);
PAINT GREEN (100 2250);
DISPLAY INVISIBLE (100 2250);
FORCEPROP 1 LAST HDL_TAP TRUE
J 2
(-225 2175);
DISPLAY 1.234043 (-225 2175);
PAINT GREEN (-225 2175);
DISPLAY INVISIBLE (-225 2175);
FORCEPROP 1 LAST PATH I82
J 2
(102 2300);
DISPLAY 0.872340 (102 2300);
PAINT GREEN (102 2300);
DISPLAY INVISIBLE (102 2300);
FORCEADD TAP..6
R 2
(100 2350);
FORCEPROP 3 LASTPIN (50 2350) SIG_NAME M_A_DQ<23>
J 0
(60 2360);
DISPLAY 0.659574 (60 2360);
PAINT MONO (60 2360);
DISPLAY INVISIBLE (60 2360);
FORCEPROP 1 LASTPIN (50 2350) BN 23
J 2
(100 2360);
DISPLAY 0.617021 (100 2360);
PAINT PINK (100 2360);
FORCEPROP 2 LAST CDS_LIB mstr_standard
J 2
(100 2350);
DISPLAY 0.787234 (100 2350);
PAINT MONO (100 2350);
DISPLAY INVISIBLE (100 2350);
FORCEPROP 1 LAST BODY_TYPE PLUMBING
J 2
(100 2300);
DISPLAY 1.234043 (100 2300);
PAINT GREEN (100 2300);
DISPLAY INVISIBLE (100 2300);
FORCEPROP 1 LAST HDL_TAP TRUE
J 2
(-225 2225);
DISPLAY 1.234043 (-225 2225);
PAINT GREEN (-225 2225);
DISPLAY INVISIBLE (-225 2225);
FORCEPROP 1 LAST PATH I83
J 2
(102 2350);
DISPLAY 0.872340 (102 2350);
PAINT GREEN (102 2350);
DISPLAY INVISIBLE (102 2350);
FORCEADD TAP..6
R 2
(100 2450);
FORCEPROP 3 LASTPIN (50 2450) SIG_NAME M_A_DQ<25>
J 0
(60 2460);
DISPLAY 0.659574 (60 2460);
PAINT MONO (60 2460);
DISPLAY INVISIBLE (60 2460);
FORCEPROP 1 LASTPIN (50 2450) BN 25
J 2
(100 2460);
DISPLAY 0.617021 (100 2460);
PAINT PINK (100 2460);
FORCEPROP 2 LAST CDS_LIB mstr_standard
J 2
(100 2450);
DISPLAY 0.787234 (100 2450);
PAINT MONO (100 2450);
DISPLAY INVISIBLE (100 2450);
FORCEPROP 1 LAST BODY_TYPE PLUMBING
J 2
(100 2400);
DISPLAY 1.234043 (100 2400);
PAINT GREEN (100 2400);
DISPLAY INVISIBLE (100 2400);
FORCEPROP 1 LAST HDL_TAP TRUE
J 2
(-225 2325);
DISPLAY 1.234043 (-225 2325);
PAINT GREEN (-225 2325);
DISPLAY INVISIBLE (-225 2325);
FORCEPROP 1 LAST PATH I84
J 2
(102 2450);
DISPLAY 0.872340 (102 2450);
PAINT GREEN (102 2450);
DISPLAY INVISIBLE (102 2450);
FORCEADD TAP..6
R 2
(100 2500);
FORCEPROP 3 LASTPIN (50 2500) SIG_NAME M_A_DQ<26>
J 0
(60 2510);
DISPLAY 0.659574 (60 2510);
PAINT MONO (60 2510);
DISPLAY INVISIBLE (60 2510);
FORCEPROP 1 LASTPIN (50 2500) BN 26
J 2
(100 2510);
DISPLAY 0.617021 (100 2510);
PAINT PINK (100 2510);
FORCEPROP 2 LAST CDS_LIB mstr_standard
J 2
(100 2500);
DISPLAY 0.787234 (100 2500);
PAINT MONO (100 2500);
DISPLAY INVISIBLE (100 2500);
FORCEPROP 1 LAST BODY_TYPE PLUMBING
J 2
(100 2450);
DISPLAY 1.234043 (100 2450);
PAINT GREEN (100 2450);
DISPLAY INVISIBLE (100 2450);
FORCEPROP 1 LAST HDL_TAP TRUE
J 2
(-225 2375);
DISPLAY 1.234043 (-225 2375);
PAINT GREEN (-225 2375);
DISPLAY INVISIBLE (-225 2375);
FORCEPROP 1 LAST PATH I85
J 2
(102 2500);
DISPLAY 0.872340 (102 2500);
PAINT GREEN (102 2500);
DISPLAY INVISIBLE (102 2500);
FORCEADD TAP..6
R 2
(100 2400);
FORCEPROP 3 LASTPIN (50 2400) SIG_NAME M_A_DQ<24>
J 0
(60 2410);
DISPLAY 0.659574 (60 2410);
PAINT MONO (60 2410);
DISPLAY INVISIBLE (60 2410);
FORCEPROP 1 LASTPIN (50 2400) BN 24
J 2
(100 2410);
DISPLAY 0.617021 (100 2410);
PAINT PINK (100 2410);
FORCEPROP 2 LAST CDS_LIB mstr_standard
J 2
(100 2400);
DISPLAY 0.787234 (100 2400);
PAINT MONO (100 2400);
DISPLAY INVISIBLE (100 2400);
FORCEPROP 1 LAST BODY_TYPE PLUMBING
J 2
(100 2350);
DISPLAY 1.234043 (100 2350);
PAINT GREEN (100 2350);
DISPLAY INVISIBLE (100 2350);
FORCEPROP 1 LAST HDL_TAP TRUE
J 2
(-225 2275);
DISPLAY 1.234043 (-225 2275);
PAINT GREEN (-225 2275);
DISPLAY INVISIBLE (-225 2275);
FORCEPROP 1 LAST PATH I86
J 2
(102 2400);
DISPLAY 0.872340 (102 2400);
PAINT GREEN (102 2400);
DISPLAY INVISIBLE (102 2400);
FORCEADD TAP..6
R 2
(100 2550);
FORCEPROP 3 LASTPIN (50 2550) SIG_NAME M_A_DQ<27>
J 0
(60 2560);
DISPLAY 0.659574 (60 2560);
PAINT MONO (60 2560);
DISPLAY INVISIBLE (60 2560);
FORCEPROP 1 LASTPIN (50 2550) BN 27
J 2
(100 2560);
DISPLAY 0.617021 (100 2560);
PAINT PINK (100 2560);
FORCEPROP 2 LAST CDS_LIB mstr_standard
J 2
(100 2550);
DISPLAY 0.787234 (100 2550);
PAINT MONO (100 2550);
DISPLAY INVISIBLE (100 2550);
FORCEPROP 1 LAST BODY_TYPE PLUMBING
J 2
(100 2500);
DISPLAY 1.234043 (100 2500);
PAINT GREEN (100 2500);
DISPLAY INVISIBLE (100 2500);
FORCEPROP 1 LAST HDL_TAP TRUE
J 2
(-225 2425);
DISPLAY 1.234043 (-225 2425);
PAINT GREEN (-225 2425);
DISPLAY INVISIBLE (-225 2425);
FORCEPROP 1 LAST PATH I87
J 2
(102 2550);
DISPLAY 0.872340 (102 2550);
PAINT GREEN (102 2550);
DISPLAY INVISIBLE (102 2550);
FORCEADD TAP..6
R 2
(100 2600);
FORCEPROP 3 LASTPIN (50 2600) SIG_NAME M_A_DQ<28>
J 0
(60 2610);
DISPLAY 0.659574 (60 2610);
PAINT MONO (60 2610);
DISPLAY INVISIBLE (60 2610);
FORCEPROP 1 LASTPIN (50 2600) BN 28
J 2
(100 2610);
DISPLAY 0.617021 (100 2610);
PAINT PINK (100 2610);
FORCEPROP 2 LAST CDS_LIB mstr_standard
J 2
(100 2600);
DISPLAY 0.787234 (100 2600);
PAINT MONO (100 2600);
DISPLAY INVISIBLE (100 2600);
FORCEPROP 1 LAST BODY_TYPE PLUMBING
J 2
(100 2550);
DISPLAY 1.234043 (100 2550);
PAINT GREEN (100 2550);
DISPLAY INVISIBLE (100 2550);
FORCEPROP 1 LAST HDL_TAP TRUE
J 2
(-225 2475);
DISPLAY 1.234043 (-225 2475);
PAINT GREEN (-225 2475);
DISPLAY INVISIBLE (-225 2475);
FORCEPROP 1 LAST PATH I88
J 2
(102 2600);
DISPLAY 0.872340 (102 2600);
PAINT GREEN (102 2600);
DISPLAY INVISIBLE (102 2600);
FORCEADD TAP..6
R 2
(100 2700);
FORCEPROP 3 LASTPIN (50 2700) SIG_NAME M_A_DQ<30>
J 0
(60 2710);
DISPLAY 0.659574 (60 2710);
PAINT MONO (60 2710);
DISPLAY INVISIBLE (60 2710);
FORCEPROP 1 LASTPIN (50 2700) BN 30
J 2
(100 2710);
DISPLAY 0.617021 (100 2710);
PAINT PINK (100 2710);
FORCEPROP 2 LAST CDS_LIB mstr_standard
J 2
(100 2700);
DISPLAY 0.787234 (100 2700);
PAINT MONO (100 2700);
DISPLAY INVISIBLE (100 2700);
FORCEPROP 1 LAST BODY_TYPE PLUMBING
J 2
(100 2650);
DISPLAY 1.234043 (100 2650);
PAINT GREEN (100 2650);
DISPLAY INVISIBLE (100 2650);
FORCEPROP 1 LAST HDL_TAP TRUE
J 2
(-225 2575);
DISPLAY 1.234043 (-225 2575);
PAINT GREEN (-225 2575);
DISPLAY INVISIBLE (-225 2575);
FORCEPROP 1 LAST PATH I89
J 2
(102 2700);
DISPLAY 0.872340 (102 2700);
PAINT GREEN (102 2700);
DISPLAY INVISIBLE (102 2700);
FORCEADD OFFPAGE..1
(-2100 900);
FORCEPROP 2 LAST $XR5 48 
J 0
(-2411 864);
DISPLAY 0.638298 (-2411 864);
PAINT MONO (-2411 864);
FORCEPROP 2 LAST $XR4 47 
J 0
(-2321 864);
DISPLAY 0.638298 (-2321 864);
PAINT MONO (-2321 864);
FORCEPROP 2 LAST $XR3 46 
J 0
(-2591 900);
DISPLAY 0.638298 (-2591 900);
PAINT MONO (-2591 900);
FORCEPROP 2 LAST $XR2 45 
J 0
(-2501 900);
DISPLAY 0.638298 (-2501 900);
PAINT MONO (-2501 900);
FORCEPROP 2 LAST $XR1 43 
J 0
(-2411 900);
DISPLAY 0.638298 (-2411 900);
PAINT MONO (-2411 900);
FORCEPROP 2 LAST $XR0 89 
J 0
(-2321 900);
DISPLAY 0.638298 (-2321 900);
PAINT MONO (-2321 900);
FORCEPROP 2 LAST CDS_LIB mstr_standard
J 0
(-2100 900);
PAINT ORANGE (-2100 900);
DISPLAY INVISIBLE (-2100 900);
FORCEPROP 1 LAST OFFPAGE TRUE
J 0
(-1775 775);
DISPLAY 0.936170 (-1775 775);
PAINT GREEN (-1775 775);
DISPLAY INVISIBLE (-1775 775);
FORCEPROP 1 LAST COMMENT_BODY TRUE
J 0
(-1975 800);
DISPLAY 0.936170 (-1975 800);
PAINT GREEN (-1975 800);
DISPLAY INVISIBLE (-1975 800);
FORCEPROP 2 LAST PATH I9
J 0
(-2350 950);
DISPLAY 1.021277 (-2350 950);
PAINT ORANGE (-2350 950);
DISPLAY INVISIBLE (-2350 950);
FORCEADD TAP..6
R 2
(100 2650);
FORCEPROP 3 LASTPIN (50 2650) SIG_NAME M_A_DQ<29>
J 0
(60 2660);
DISPLAY 0.659574 (60 2660);
PAINT MONO (60 2660);
DISPLAY INVISIBLE (60 2660);
FORCEPROP 1 LASTPIN (50 2650) BN 29
J 2
(100 2660);
DISPLAY 0.617021 (100 2660);
PAINT PINK (100 2660);
FORCEPROP 2 LAST CDS_LIB mstr_standard
J 2
(100 2650);
DISPLAY 0.787234 (100 2650);
PAINT MONO (100 2650);
DISPLAY INVISIBLE (100 2650);
FORCEPROP 1 LAST BODY_TYPE PLUMBING
J 2
(100 2600);
DISPLAY 1.234043 (100 2600);
PAINT GREEN (100 2600);
DISPLAY INVISIBLE (100 2600);
FORCEPROP 1 LAST HDL_TAP TRUE
J 2
(-225 2525);
DISPLAY 1.234043 (-225 2525);
PAINT GREEN (-225 2525);
DISPLAY INVISIBLE (-225 2525);
FORCEPROP 1 LAST PATH I90
J 2
(102 2650);
DISPLAY 0.872340 (102 2650);
PAINT GREEN (102 2650);
DISPLAY INVISIBLE (102 2650);
FORCEADD TAP..6
R 2
(100 2750);
FORCEPROP 3 LASTPIN (50 2750) SIG_NAME M_A_DQ<31>
J 0
(60 2760);
DISPLAY 0.659574 (60 2760);
PAINT MONO (60 2760);
DISPLAY INVISIBLE (60 2760);
FORCEPROP 1 LASTPIN (50 2750) BN 31
J 2
(100 2760);
DISPLAY 0.617021 (100 2760);
PAINT PINK (100 2760);
FORCEPROP 2 LAST CDS_LIB mstr_standard
J 2
(100 2750);
DISPLAY 0.787234 (100 2750);
PAINT MONO (100 2750);
DISPLAY INVISIBLE (100 2750);
FORCEPROP 1 LAST BODY_TYPE PLUMBING
J 2
(100 2700);
DISPLAY 1.234043 (100 2700);
PAINT GREEN (100 2700);
DISPLAY INVISIBLE (100 2700);
FORCEPROP 1 LAST HDL_TAP TRUE
J 2
(-225 2625);
DISPLAY 1.234043 (-225 2625);
PAINT GREEN (-225 2625);
DISPLAY INVISIBLE (-225 2625);
FORCEPROP 1 LAST PATH I91
J 2
(102 2750);
DISPLAY 0.872340 (102 2750);
PAINT GREEN (102 2750);
DISPLAY INVISIBLE (102 2750);
FORCEADD TAP..6
R 2
(100 2800);
FORCEPROP 3 LASTPIN (50 2800) SIG_NAME M_A_DQ<32>
J 0
(60 2810);
DISPLAY 0.659574 (60 2810);
PAINT MONO (60 2810);
DISPLAY INVISIBLE (60 2810);
FORCEPROP 1 LASTPIN (50 2800) BN 32
J 2
(100 2810);
DISPLAY 0.617021 (100 2810);
PAINT PINK (100 2810);
FORCEPROP 2 LAST CDS_LIB mstr_standard
J 2
(100 2800);
DISPLAY 0.787234 (100 2800);
PAINT MONO (100 2800);
DISPLAY INVISIBLE (100 2800);
FORCEPROP 1 LAST BODY_TYPE PLUMBING
J 2
(100 2750);
DISPLAY 1.234043 (100 2750);
PAINT GREEN (100 2750);
DISPLAY INVISIBLE (100 2750);
FORCEPROP 1 LAST HDL_TAP TRUE
J 2
(-225 2675);
DISPLAY 1.234043 (-225 2675);
PAINT GREEN (-225 2675);
DISPLAY INVISIBLE (-225 2675);
FORCEPROP 1 LAST PATH I92
J 2
(102 2800);
DISPLAY 0.872340 (102 2800);
PAINT GREEN (102 2800);
DISPLAY INVISIBLE (102 2800);
FORCEADD TAP..6
R 2
(100 2850);
FORCEPROP 3 LASTPIN (50 2850) SIG_NAME M_A_DQ<33>
J 0
(60 2860);
DISPLAY 0.659574 (60 2860);
PAINT MONO (60 2860);
DISPLAY INVISIBLE (60 2860);
FORCEPROP 1 LASTPIN (50 2850) BN 33
J 2
(100 2860);
DISPLAY 0.617021 (100 2860);
PAINT PINK (100 2860);
FORCEPROP 2 LAST CDS_LIB mstr_standard
J 2
(100 2850);
DISPLAY 0.787234 (100 2850);
PAINT MONO (100 2850);
DISPLAY INVISIBLE (100 2850);
FORCEPROP 1 LAST BODY_TYPE PLUMBING
J 2
(100 2800);
DISPLAY 1.234043 (100 2800);
PAINT GREEN (100 2800);
DISPLAY INVISIBLE (100 2800);
FORCEPROP 1 LAST HDL_TAP TRUE
J 2
(-225 2725);
DISPLAY 1.234043 (-225 2725);
PAINT GREEN (-225 2725);
DISPLAY INVISIBLE (-225 2725);
FORCEPROP 1 LAST PATH I93
J 2
(102 2850);
DISPLAY 0.872340 (102 2850);
PAINT GREEN (102 2850);
DISPLAY INVISIBLE (102 2850);
FORCEADD TAP..6
R 2
(100 2900);
FORCEPROP 3 LASTPIN (50 2900) SIG_NAME M_A_DQ<34>
J 0
(60 2910);
DISPLAY 0.659574 (60 2910);
PAINT MONO (60 2910);
DISPLAY INVISIBLE (60 2910);
FORCEPROP 1 LASTPIN (50 2900) BN 34
J 2
(100 2910);
DISPLAY 0.617021 (100 2910);
PAINT PINK (100 2910);
FORCEPROP 2 LAST CDS_LIB mstr_standard
J 2
(100 2900);
DISPLAY 0.787234 (100 2900);
PAINT MONO (100 2900);
DISPLAY INVISIBLE (100 2900);
FORCEPROP 1 LAST BODY_TYPE PLUMBING
J 2
(100 2850);
DISPLAY 1.234043 (100 2850);
PAINT GREEN (100 2850);
DISPLAY INVISIBLE (100 2850);
FORCEPROP 1 LAST HDL_TAP TRUE
J 2
(-225 2775);
DISPLAY 1.234043 (-225 2775);
PAINT GREEN (-225 2775);
DISPLAY INVISIBLE (-225 2775);
FORCEPROP 1 LAST PATH I94
J 2
(102 2900);
DISPLAY 0.872340 (102 2900);
PAINT GREEN (102 2900);
DISPLAY INVISIBLE (102 2900);
FORCEADD TAP..6
R 2
(100 2950);
FORCEPROP 3 LASTPIN (50 2950) SIG_NAME M_A_DQ<35>
J 0
(60 2960);
DISPLAY 0.659574 (60 2960);
PAINT MONO (60 2960);
DISPLAY INVISIBLE (60 2960);
FORCEPROP 1 LASTPIN (50 2950) BN 35
J 2
(100 2960);
DISPLAY 0.617021 (100 2960);
PAINT PINK (100 2960);
FORCEPROP 2 LAST CDS_LIB mstr_standard
J 2
(100 2950);
DISPLAY 0.787234 (100 2950);
PAINT MONO (100 2950);
DISPLAY INVISIBLE (100 2950);
FORCEPROP 1 LAST BODY_TYPE PLUMBING
J 2
(100 2900);
DISPLAY 1.234043 (100 2900);
PAINT GREEN (100 2900);
DISPLAY INVISIBLE (100 2900);
FORCEPROP 1 LAST HDL_TAP TRUE
J 2
(-225 2825);
DISPLAY 1.234043 (-225 2825);
PAINT GREEN (-225 2825);
DISPLAY INVISIBLE (-225 2825);
FORCEPROP 1 LAST PATH I95
J 2
(102 2950);
DISPLAY 0.872340 (102 2950);
PAINT GREEN (102 2950);
DISPLAY INVISIBLE (102 2950);
FORCEADD TAP..6
R 2
(100 3000);
FORCEPROP 3 LASTPIN (50 3000) SIG_NAME M_A_DQ<36>
J 0
(60 3010);
DISPLAY 0.659574 (60 3010);
PAINT MONO (60 3010);
DISPLAY INVISIBLE (60 3010);
FORCEPROP 1 LASTPIN (50 3000) BN 36
J 2
(100 3010);
DISPLAY 0.617021 (100 3010);
PAINT PINK (100 3010);
FORCEPROP 2 LAST CDS_LIB mstr_standard
J 2
(100 3000);
DISPLAY 0.787234 (100 3000);
PAINT MONO (100 3000);
DISPLAY INVISIBLE (100 3000);
FORCEPROP 1 LAST BODY_TYPE PLUMBING
J 2
(100 2950);
DISPLAY 1.234043 (100 2950);
PAINT GREEN (100 2950);
DISPLAY INVISIBLE (100 2950);
FORCEPROP 1 LAST HDL_TAP TRUE
J 2
(-225 2875);
DISPLAY 1.234043 (-225 2875);
PAINT GREEN (-225 2875);
DISPLAY INVISIBLE (-225 2875);
FORCEPROP 1 LAST PATH I96
J 2
(102 3000);
DISPLAY 0.872340 (102 3000);
PAINT GREEN (102 3000);
DISPLAY INVISIBLE (102 3000);
FORCEADD PVDDQ_ABC..1
(600 2200);
FORCEPROP 3 LASTPIN (600 2150) SIG_NAME PVDDQ_ABC\g
J 0
(610 2160);
DISPLAY 0.659574 (610 2160);
PAINT MONO (610 2160);
DISPLAY INVISIBLE (610 2160);
FORCEPROP 1 LAST VOLTAGE 1.2V
J 0
(555 2157);
DISPLAY 0.340426 (555 2157);
PAINT SKYBLUE (555 2157);
DISPLAY INVISIBLE (555 2157);
FORCEPROP 2 LAST BOM_COST MEM
J 0
(600 2205);
PAINT ORANGE (600 2205);
DISPLAY INVISIBLE (600 2205);
FORCEPROP 2 LAST CDS_LIB mstr_symbols
J 0
(600 2200);
PAINT ORANGE (600 2200);
DISPLAY INVISIBLE (600 2200);
FORCEPROP 1 LAST BODY_TYPE PLUMBING
J 0
(555 2157);
DISPLAY 0.340426 (555 2157);
PAINT GREEN (555 2157);
DISPLAY INVISIBLE (555 2157);
FORCEPROP 1 LAST PATH I97
J 0
(650 2225);
DISPLAY 0.872340 (650 2225);
PAINT AQUA (650 2225);
DISPLAY INVISIBLE (650 2225);
FORCEPROP 2 LAST ROOM DDR4_CH_A
J 0
(600 2300);
DISPLAY 0.787234 (600 2300);
PAINT ORANGE (600 2300);
DISPLAY INVISIBLE (600 2300);
FORCEPROP 1 LAST HDL_POWER PVDDQ_ABC
J 1
(600 2250);
DISPLAY 0.872340 (600 2250);
PAINT GREEN (600 2250);
DISPLAY INVISIBLE (600 2250);
FORCEADD TAP..6
R 2
(100 3050);
FORCEPROP 3 LASTPIN (50 3050) SIG_NAME M_A_DQ<37>
J 0
(60 3060);
DISPLAY 0.659574 (60 3060);
PAINT MONO (60 3060);
DISPLAY INVISIBLE (60 3060);
FORCEPROP 1 LASTPIN (50 3050) BN 37
J 2
(100 3060);
DISPLAY 0.617021 (100 3060);
PAINT PINK (100 3060);
FORCEPROP 2 LAST CDS_LIB mstr_standard
J 2
(100 3050);
DISPLAY 0.787234 (100 3050);
PAINT MONO (100 3050);
DISPLAY INVISIBLE (100 3050);
FORCEPROP 1 LAST BODY_TYPE PLUMBING
J 2
(100 3000);
DISPLAY 1.234043 (100 3000);
PAINT GREEN (100 3000);
DISPLAY INVISIBLE (100 3000);
FORCEPROP 1 LAST HDL_TAP TRUE
J 2
(-225 2925);
DISPLAY 1.234043 (-225 2925);
PAINT GREEN (-225 2925);
DISPLAY INVISIBLE (-225 2925);
FORCEPROP 1 LAST PATH I98
J 2
(102 3050);
DISPLAY 0.872340 (102 3050);
PAINT GREEN (102 3050);
DISPLAY INVISIBLE (102 3050);
FORCEADD TAP..6
R 2
(100 3100);
FORCEPROP 3 LASTPIN (50 3100) SIG_NAME M_A_DQ<38>
J 0
(60 3110);
DISPLAY 0.659574 (60 3110);
PAINT MONO (60 3110);
DISPLAY INVISIBLE (60 3110);
FORCEPROP 1 LASTPIN (50 3100) BN 38
J 2
(100 3110);
DISPLAY 0.617021 (100 3110);
PAINT PINK (100 3110);
FORCEPROP 2 LAST CDS_LIB mstr_standard
J 2
(100 3100);
DISPLAY 0.787234 (100 3100);
PAINT MONO (100 3100);
DISPLAY INVISIBLE (100 3100);
FORCEPROP 1 LAST BODY_TYPE PLUMBING
J 2
(100 3050);
DISPLAY 1.234043 (100 3050);
PAINT GREEN (100 3050);
DISPLAY INVISIBLE (100 3050);
FORCEPROP 1 LAST HDL_TAP TRUE
J 2
(-225 2975);
DISPLAY 1.234043 (-225 2975);
PAINT GREEN (-225 2975);
DISPLAY INVISIBLE (-225 2975);
FORCEPROP 1 LAST PATH I99
J 2
(102 3100);
DISPLAY 0.872340 (102 3100);
PAINT GREEN (102 3100);
DISPLAY INVISIBLE (102 3100);
FORCEADD INTEL_CORP_BPAGE..1
(4250 200);
FORCEPROP 1 LAST CDS_CON_LAST_MODIFIED Fri Jun 16 17:48:16 2017
J 0
(2825 525);
PAINT ORANGE (2825 525);
DISPLAY INVISIBLE (2825 525);
FORCEPROP 1 LAST CUSTOM_TXT_CDS <CURRENT_DESIGN_SHEET> OF <TOTAL_DESIGN_SHEETS>
J 0
(3750 225);
PAINT ORANGE (3750 225);
FORCEPROP 1 LAST CUSTOM_TXT_CDS <CON_LAST_MODIFIED>
J 0
(250 300);
PAINT ORANGE (250 300);
FORCEPROP 2 LAST CUSTOM_TXT_CDS <XR_PAGE_TITLE>
J 0
(-3640 5450);
DISPLAY 0.638298 (-3640 5450);
PAINT PINK (-3640 5450);
DISPLAY INVISIBLE (-3640 5450);
FORCEPROP 1 LAST SCH_TITLE CPU0 DDR4 CH A DIMM1
J 0
(-3700 250);
DISPLAY 1.212766 (-3700 250);
PAINT ORANGE (-3700 250);
FORCEPROP 2 LAST PAGE_BORDER TRUE
J 0
(-3640 5450);
DISPLAY 0.638298 (-3640 5450);
PAINT PINK (-3640 5450);
DISPLAY INVISIBLE (-3640 5450);
FORCEPROP 2 LAST CDS_LIB mstr_symbols
J 0
(4250 200);
PAINT MONO (4250 200);
DISPLAY INVISIBLE (4250 200);
FORCEPROP 1 LAST COMMENT_BODY TRUE
J 0
(4262 212);
DISPLAY 0.468085 (4262 212);
PAINT GREEN (4262 212);
DISPLAY INVISIBLE (4262 212);
FORCEPROP 2 LAST CDS_XR_PAGE_TITLE CR-44 : @BASEBOARD_FAB2_LIB.BASEBOARD_FAB2(SCH_1):PAGE44
J 0
(-3640 5450);
DISPLAY 0.638298 (-3640 5450);
PAINT PINK (-3640 5450);
DISPLAY INVISIBLE (-3640 5450);
FORCEADD BOM_NOTE..1
(-3325 4925);
FORCEPROP 0 LAST L1 UNSTUFF FOR SKU B
J 0
(-3475 4825);
DISPLAY 1.063830 (-3475 4825);
PAINT WHITE (-3475 4825);
FORCEPROP 2 LAST CDS_LIB mstr_symbols
J 0
(-3325 4925);
PAINT ORANGE (-3325 4925);
DISPLAY INVISIBLE (-3325 4925);
FORCEPROP 2 LAST BOM_COST SB
J 0
(-3475 4900);
DISPLAY 1.361702 (-3475 4900);
PAINT ORANGE (-3475 4900);
DISPLAY INVISIBLE (-3475 4900);
FORCEPROP 1 LAST COMMENT_BODY TRUE
J 0
(-3300 5025);
DISPLAY 1.319149 (-3300 5025);
PAINT ORANGE (-3300 5025);
DISPLAY INVISIBLE (-3300 5025);
FORCEPROP 2 LAST ROOM SB_HEADERS
J 0
(-3475 4900);
DISPLAY 1.361702 (-3475 4900);
PAINT ORANGE (-3475 4900);
DISPLAY INVISIBLE (-3475 4900);
WIRE 16 -1 (-2650 900)(-2650 800);
WIRE 16 -1 (800 2200)(800 2300);
WIRE 16 -1 (800 2200)(950 2200);
WIRE 16 -1 (950 2150)(950 2200);
WIRE 16 -1 (950 2200)(1100 2200);
WIRE 16 -1 (1100 2150)(950 2150);
WIRE 16 -1 (950 2600)(950 2500);
WIRE 16 -1 (950 2500)(950 2450);
WIRE 16 -1 (950 2500)(1100 2500);
WIRE 16 -1 (950 2400)(950 2450);
WIRE 16 -1 (950 2450)(1100 2450);
WIRE 16 -1 (950 2350)(950 2400);
WIRE 16 -1 (950 2400)(1100 2400);
WIRE 16 -1 (950 2300)(950 2350);
WIRE 16 -1 (950 2350)(1100 2350);
WIRE 16 -1 (950 2300)(1100 2300);
WIRE 16 -1 (2750 1150)(2750 1250);
WIRE 16 -1 (2750 1250)(2750 1300);
WIRE 16 -1 (2750 1250)(2950 1250);
WIRE 16 -1 (2750 1300)(2750 1350);
WIRE 16 -1 (2750 1300)(2950 1300);
WIRE 16 -1 (2750 1350)(2750 1400);
WIRE 16 -1 (2750 1350)(2950 1350);
WIRE 16 -1 (2750 1400)(2750 1450);
WIRE 16 -1 (2750 1400)(2950 1400);
WIRE 16 -1 (2750 1450)(2750 1500);
WIRE 16 -1 (2750 1450)(2950 1450);
WIRE 16 -1 (2750 1500)(2750 1550);
WIRE 16 -1 (2750 1500)(2950 1500);
WIRE 16 -1 (2750 1550)(2750 1600);
WIRE 16 -1 (2750 1550)(2950 1550);
WIRE 16 -1 (2750 1600)(2750 1650);
WIRE 16 -1 (2750 1600)(2950 1600);
WIRE 16 -1 (2750 1650)(2750 1700);
WIRE 16 -1 (2750 1650)(2950 1650);
WIRE 16 -1 (2750 1700)(2750 1750);
WIRE 16 -1 (2750 1700)(2950 1700);
WIRE 16 -1 (2750 1750)(2750 1800);
WIRE 16 -1 (2750 1750)(2950 1750);
WIRE 16 -1 (2750 1800)(2750 1850);
WIRE 16 -1 (2750 1800)(2950 1800);
WIRE 16 -1 (2750 1850)(2750 1900);
WIRE 16 -1 (2750 1850)(2950 1850);
WIRE 16 -1 (2750 1900)(2750 1950);
WIRE 16 -1 (2750 1900)(2950 1900);
WIRE 16 -1 (2750 1950)(2750 2000);
WIRE 16 -1 (2750 1950)(2950 1950);
WIRE 16 -1 (2750 2000)(2750 2050);
WIRE 16 -1 (2750 2000)(2950 2000);
WIRE 16 -1 (2750 2050)(2750 2100);
WIRE 16 -1 (2750 2050)(2950 2050);
WIRE 16 -1 (2750 2100)(2750 2150);
WIRE 16 -1 (2750 2100)(2950 2100);
WIRE 16 -1 (2750 2150)(2750 2200);
WIRE 16 -1 (2750 2150)(2950 2150);
WIRE 16 -1 (2750 2200)(2750 2250);
WIRE 16 -1 (2750 2200)(2950 2200);
WIRE 16 -1 (2750 2250)(2750 2300);
WIRE 16 -1 (2750 2250)(2950 2250);
WIRE 16 -1 (2750 2300)(2750 2350);
WIRE 16 -1 (2750 2300)(2950 2300);
WIRE 16 -1 (2750 2350)(2750 2400);
WIRE 16 -1 (2750 2350)(2950 2350);
WIRE 16 -1 (2750 2400)(2750 2450);
WIRE 16 -1 (2750 2400)(2950 2400);
WIRE 16 -1 (2750 2450)(2750 2500);
WIRE 16 -1 (2750 2450)(2950 2450);
WIRE 16 -1 (2750 2500)(2750 2550);
WIRE 16 -1 (2750 2500)(2950 2500);
WIRE 16 -1 (2750 2550)(2750 2600);
WIRE 16 -1 (2750 2550)(2950 2550);
WIRE 16 -1 (2750 2600)(2750 2650);
WIRE 16 -1 (2750 2600)(2950 2600);
WIRE 16 -1 (2750 2650)(2750 2700);
WIRE 16 -1 (2750 2650)(2950 2650);
WIRE 16 -1 (2750 2700)(2750 2750);
WIRE 16 -1 (2750 2700)(2950 2700);
WIRE 16 -1 (2750 2750)(2750 2800);
WIRE 16 -1 (2750 2750)(2950 2750);
WIRE 16 -1 (2750 2800)(2750 2850);
WIRE 16 -1 (2750 2800)(2950 2800);
WIRE 16 -1 (2750 2850)(2750 2900);
WIRE 16 -1 (2750 2850)(2950 2850);
WIRE 16 -1 (2750 2900)(2750 2950);
WIRE 16 -1 (2750 2900)(2950 2900);
WIRE 16 -1 (2750 2950)(2750 3000);
WIRE 16 -1 (2750 2950)(2950 2950);
WIRE 16 -1 (2750 3000)(2750 3050);
WIRE 16 -1 (2750 3000)(2950 3000);
WIRE 16 -1 (2750 3050)(2750 3100);
WIRE 16 -1 (2750 3050)(2950 3050);
WIRE 16 -1 (2750 3100)(2750 3150);
WIRE 16 -1 (2750 3100)(2950 3100);
WIRE 16 -1 (2750 3150)(2750 3200);
WIRE 16 -1 (2750 3150)(2950 3150);
WIRE 16 -1 (2750 3200)(2750 3250);
WIRE 16 -1 (2750 3200)(2950 3200);
WIRE 16 -1 (2750 3250)(2750 3300);
WIRE 16 -1 (2750 3250)(2950 3250);
WIRE 16 -1 (2750 3300)(2750 3350);
WIRE 16 -1 (2750 3300)(2950 3300);
WIRE 16 -1 (2750 3350)(2750 3400);
WIRE 16 -1 (2750 3350)(2950 3350);
WIRE 16 -1 (2750 3400)(2750 3450);
WIRE 16 -1 (2750 3400)(2950 3400);
WIRE 16 -1 (2750 3450)(2750 3500);
WIRE 16 -1 (2750 3450)(2950 3450);
WIRE 16 -1 (2750 3500)(2750 3550);
WIRE 16 -1 (2750 3500)(2950 3500);
WIRE 16 -1 (2750 3550)(2950 3550);
WIRE 16 -1 (4150 1150)(4150 1250);
WIRE 16 -1 (4150 1250)(4150 1300);
WIRE 16 -1 (4150 1250)(3950 1250);
WIRE 16 -1 (4150 1300)(4150 1350);
WIRE 16 -1 (4150 1300)(3950 1300);
WIRE 16 -1 (4150 1350)(4150 1400);
WIRE 16 -1 (4150 1350)(3950 1350);
WIRE 16 -1 (4150 1400)(4150 1450);
WIRE 16 -1 (4150 1400)(3950 1400);
WIRE 16 -1 (4150 1450)(4150 1500);
WIRE 16 -1 (4150 1450)(3950 1450);
WIRE 16 -1 (4150 1500)(4150 1550);
WIRE 16 -1 (4150 1500)(3950 1500);
WIRE 16 -1 (4150 1550)(4150 1600);
WIRE 16 -1 (4150 1550)(3950 1550);
WIRE 16 -1 (4150 1600)(4150 1650);
WIRE 16 -1 (4150 1600)(3950 1600);
WIRE 16 -1 (4150 1650)(4150 1700);
WIRE 16 -1 (4150 1650)(3950 1650);
WIRE 16 -1 (4150 1700)(4150 1750);
WIRE 16 -1 (4150 1700)(3950 1700);
WIRE 16 -1 (4150 1750)(4150 1800);
WIRE 16 -1 (4150 1750)(3950 1750);
WIRE 16 -1 (4150 1800)(4150 1850);
WIRE 16 -1 (4150 1800)(3950 1800);
WIRE 16 -1 (4150 1850)(4150 1900);
WIRE 16 -1 (4150 1850)(3950 1850);
WIRE 16 -1 (4150 1900)(4150 1950);
WIRE 16 -1 (4150 1900)(3950 1900);
WIRE 16 -1 (4150 1950)(4150 2000);
WIRE 16 -1 (4150 1950)(3950 1950);
WIRE 16 -1 (4150 2000)(4150 2050);
WIRE 16 -1 (4150 2000)(3950 2000);
WIRE 16 -1 (4150 2050)(4150 2100);
WIRE 16 -1 (4150 2050)(3950 2050);
WIRE 16 -1 (4150 2100)(4150 2150);
WIRE 16 -1 (4150 2100)(3950 2100);
WIRE 16 -1 (4150 2150)(4150 2200);
WIRE 16 -1 (4150 2150)(3950 2150);
WIRE 16 -1 (4150 2200)(4150 2250);
WIRE 16 -1 (4150 2200)(3950 2200);
WIRE 16 -1 (4150 2250)(4150 2300);
WIRE 16 -1 (4150 2250)(3950 2250);
WIRE 16 -1 (4150 2300)(4150 2350);
WIRE 16 -1 (4150 2300)(3950 2300);
WIRE 16 -1 (4150 2350)(4150 2400);
WIRE 16 -1 (4150 2350)(3950 2350);
WIRE 16 -1 (4150 2400)(4150 2450);
WIRE 16 -1 (4150 2400)(3950 2400);
WIRE 16 -1 (4150 2450)(4150 2500);
WIRE 16 -1 (4150 2450)(3950 2450);
WIRE 16 -1 (4150 2500)(4150 2550);
WIRE 16 -1 (4150 2500)(3950 2500);
WIRE 16 -1 (4150 2550)(4150 2600);
WIRE 16 -1 (4150 2550)(3950 2550);
WIRE 16 -1 (4150 2600)(4150 2650);
WIRE 16 -1 (4150 2600)(3950 2600);
WIRE 16 -1 (4150 2650)(4150 2700);
WIRE 16 -1 (4150 2650)(3950 2650);
WIRE 16 -1 (4150 2700)(4150 2750);
WIRE 16 -1 (4150 2700)(3950 2700);
WIRE 16 -1 (4150 2750)(4150 2800);
WIRE 16 -1 (4150 2750)(3950 2750);
WIRE 16 -1 (4150 2800)(4150 2850);
WIRE 16 -1 (4150 2800)(3950 2800);
WIRE 16 -1 (4150 2850)(4150 2900);
WIRE 16 -1 (4150 2850)(3950 2850);
WIRE 16 -1 (4150 2900)(4150 2950);
WIRE 16 -1 (4150 2900)(3950 2900);
WIRE 16 -1 (4150 2950)(4150 3000);
WIRE 16 -1 (4150 2950)(3950 2950);
WIRE 16 -1 (4150 3000)(4150 3050);
WIRE 16 -1 (4150 3000)(3950 3000);
WIRE 16 -1 (4150 3050)(4150 3100);
WIRE 16 -1 (4150 3050)(3950 3050);
WIRE 16 -1 (4150 3100)(4150 3150);
WIRE 16 -1 (4150 3100)(3950 3100);
WIRE 16 -1 (4150 3150)(4150 3200);
WIRE 16 -1 (4150 3150)(3950 3150);
WIRE 16 -1 (4150 3200)(4150 3250);
WIRE 16 -1 (4150 3200)(3950 3200);
WIRE 16 -1 (4150 3250)(4150 3300);
WIRE 16 -1 (4150 3250)(3950 3250);
WIRE 16 -1 (4150 3300)(4150 3350);
WIRE 16 -1 (4150 3300)(3950 3300);
WIRE 16 -1 (4150 3350)(4150 3400);
WIRE 16 -1 (4150 3350)(3950 3350);
WIRE 16 -1 (4150 3400)(4150 3450);
WIRE 16 -1 (4150 3400)(3950 3400);
WIRE 16 -1 (4150 3450)(4150 3500);
WIRE 16 -1 (4150 3450)(3950 3450);
WIRE 16 -1 (4150 3500)(4150 3550);
WIRE 16 -1 (4150 3500)(3950 3500);
WIRE 16 -1 (4150 3550)(3950 3550);
WIRE 16 -1 (2300 2500)(2300 2675);
WIRE 16 -1 (2300 2450)(2300 2500);
WIRE 16 -1 (2300 2500)(2100 2500);
WIRE 16 -1 (2100 2450)(2300 2450);
WIRE 16 -1 (-3350 1500)(-3350 1400);
WIRE 16 -1 (-3350 1500)(-1400 1500);
WIRE 16 -1 (-1400 1500)(-1400 1450);
WIRE 16 -1 (-1400 1500)(-1200 1500);
WIRE 16 -1 (-1400 1450)(-1200 1450);
WIRE 16 -1 (-3350 1650)(-3350 1550);
WIRE 16 -1 (-1500 1550)(-3350 1550);
WIRE 16 -1 (-1500 1550)(-1500 1400);
WIRE 16 -1 (-1200 1550)(-1500 1550);
WIRE 16 -1 (-1500 1400)(-1200 1400);
WIRE 16 -1 (600 2150)(600 2050);
WIRE 16 -1 (600 2050)(950 2050);
WIRE 16 -1 (950 2000)(950 2050);
WIRE 16 -1 (950 2050)(1100 2050);
WIRE 16 -1 (950 1950)(950 2000);
WIRE 16 -1 (950 2000)(1100 2000);
WIRE 16 -1 (950 1900)(950 1950);
WIRE 16 -1 (950 1950)(1100 1950);
WIRE 16 -1 (950 1850)(950 1900);
WIRE 16 -1 (950 1900)(1100 1900);
WIRE 16 -1 (950 1800)(950 1850);
WIRE 16 -1 (950 1850)(1100 1850);
WIRE 16 -1 (950 1750)(950 1800);
WIRE 16 -1 (950 1800)(1100 1800);
WIRE 16 -1 (950 1700)(950 1750);
WIRE 16 -1 (950 1750)(1100 1750);
WIRE 16 -1 (950 1650)(950 1700);
WIRE 16 -1 (950 1700)(1100 1700);
WIRE 16 -1 (950 1600)(950 1650);
WIRE 16 -1 (950 1650)(1100 1650);
WIRE 16 -1 (950 1550)(950 1600);
WIRE 16 -1 (950 1600)(1100 1600);
WIRE 16 -1 (950 1500)(950 1550);
WIRE 16 -1 (950 1550)(1100 1550);
WIRE 16 -1 (950 1450)(950 1500);
WIRE 16 -1 (950 1500)(1100 1500);
WIRE 16 -1 (950 1400)(950 1450);
WIRE 16 -1 (950 1450)(1100 1450);
WIRE 16 -1 (950 1350)(950 1400);
WIRE 16 -1 (950 1400)(1100 1400);
WIRE 16 -1 (950 1300)(950 1350);
WIRE 16 -1 (950 1350)(1100 1350);
WIRE 16 -1 (950 1250)(950 1300);
WIRE 16 -1 (950 1300)(1100 1300);
WIRE 16 -1 (950 1200)(950 1250);
WIRE 16 -1 (950 1250)(1100 1250);
WIRE 16 -1 (950 1150)(950 1200);
WIRE 16 -1 (950 1200)(1100 1200);
WIRE 16 -1 (950 1100)(950 1150);
WIRE 16 -1 (950 1150)(1100 1150);
WIRE 16 -1 (950 1050)(950 1100);
WIRE 16 -1 (950 1100)(1100 1100);
WIRE 16 -1 (950 1000)(950 1050);
WIRE 16 -1 (950 1050)(1100 1050);
WIRE 16 -1 (950 950)(950 1000);
WIRE 16 -1 (950 1000)(1100 1000);
WIRE 16 -1 (950 900)(950 950);
WIRE 16 -1 (950 950)(1100 950);
WIRE 16 -1 (950 850)(950 900);
WIRE 16 -1 (950 900)(1100 900);
WIRE 16 -1 (950 800)(950 850);
WIRE 16 -1 (950 850)(1100 850);
WIRE 16 -1 (950 800)(1100 800);
WIRE 17 -1 (2600 3125)(2600 3225);
WIRE 17 -1 (2600 3225)(2600 3325);
WIRE 17 -1 (2600 3325)(2600 3425);
WIRE 17 -1 (2600 3425)(2600 3525);
WIRE 17 -1 (2600 3525)(2600 3625);
WIRE 17 -1 (2600 3625)(2600 3725);
WIRE 17 -1 (2600 3725)(2600 3825);
WIRE 17 -1 (2600 3825)(2600 3925);
WIRE 17 -1 (2600 3925)(2600 4025);
WIRE 17 -1 (2600 4025)(2600 4125);
WIRE 17 -1 (2600 4125)(2600 4225);
WIRE 17 -1 (2600 4225)(2600 4325);
WIRE 17 -1 (2600 4325)(2600 4425);
WIRE 17 -1 (2600 4425)(2600 4525);
WIRE 17 -1 (2600 4525)(2600 4625);
WIRE 17 -1 (3200 4850)(2600 4850);
FORCEPROP 2 LAST SIG_NAME M_A_DQS_DN<17:0>
J 0
(2650 4860);
DISPLAY 0.617021 (2650 4860);
PAINT ORANGE (2650 4860);
WIRE 17 -1 (2600 4825)(2600 4850);
WIRE 17 -1 (2600 4625)(2600 4725);
WIRE 17 -1 (2600 4725)(2600 4825);
WIRE 17 -1 (2400 3175)(2400 3275);
WIRE 17 -1 (2400 3275)(2400 3375);
WIRE 17 -1 (2400 3375)(2400 3475);
WIRE 17 -1 (2400 3475)(2400 3575);
WIRE 17 -1 (2400 3575)(2400 3675);
WIRE 17 -1 (2400 3675)(2400 3775);
WIRE 17 -1 (2400 3775)(2400 3875);
WIRE 17 -1 (2400 3875)(2400 3975);
WIRE 17 -1 (2400 3975)(2400 4075);
WIRE 17 -1 (2400 4075)(2400 4175);
WIRE 17 -1 (2400 4175)(2400 4275);
WIRE 17 -1 (3200 4900)(2400 4900);
FORCEPROP 2 LAST SIG_NAME M_A_DQS_DP<17:0>
J 0
(2650 4910);
DISPLAY 0.617021 (2650 4910);
PAINT ORANGE (2650 4910);
WIRE 17 -1 (2400 4875)(2400 4900);
WIRE 17 -1 (2400 4275)(2400 4375);
WIRE 17 -1 (2400 4375)(2400 4475);
WIRE 17 -1 (2400 4775)(2400 4875);
WIRE 17 -1 (2400 4675)(2400 4775);
WIRE 17 -1 (2400 4475)(2400 4575);
WIRE 17 -1 (2400 4575)(2400 4675);
WIRE 17 -1 (650 4400)(150 4400);
FORCEPROP 2 LAST SIG_NAME M_A_DQ<63:0>
J 0
(190 4410);
DISPLAY 0.617021 (190 4410);
PAINT ORANGE (190 4410);
WIRE 17 -1 (150 4375)(150 4400);
WIRE 17 -1 (150 4325)(150 4375);
WIRE 17 -1 (150 4275)(150 4325);
WIRE 17 -1 (150 4225)(150 4275);
WIRE 17 -1 (150 4175)(150 4225);
WIRE 17 -1 (150 4125)(150 4175);
WIRE 17 -1 (150 4075)(150 4125);
WIRE 17 -1 (150 4025)(150 4075);
WIRE 17 -1 (150 3975)(150 4025);
WIRE 17 -1 (150 3925)(150 3975);
WIRE 17 -1 (150 3875)(150 3925);
WIRE 17 -1 (150 3825)(150 3875);
WIRE 17 -1 (150 3775)(150 3825);
WIRE 17 -1 (150 3725)(150 3775);
WIRE 17 -1 (150 3675)(150 3725);
WIRE 17 -1 (150 3625)(150 3675);
WIRE 17 -1 (150 3575)(150 3625);
WIRE 17 -1 (150 3525)(150 3575);
WIRE 17 -1 (150 3475)(150 3525);
WIRE 17 -1 (150 3425)(150 3475);
WIRE 17 -1 (150 3375)(150 3425);
WIRE 17 -1 (150 3325)(150 3375);
WIRE 17 -1 (150 3275)(150 3325);
WIRE 17 -1 (150 3225)(150 3275);
WIRE 17 -1 (150 3175)(150 3225);
WIRE 17 -1 (150 3125)(150 3175);
WIRE 17 -1 (150 3075)(150 3125);
WIRE 17 -1 (150 3025)(150 3075);
WIRE 17 -1 (150 2975)(150 3025);
WIRE 17 -1 (150 2925)(150 2975);
WIRE 17 -1 (150 2875)(150 2925);
WIRE 17 -1 (150 2825)(150 2875);
WIRE 17 -1 (150 2775)(150 2825);
WIRE 17 -1 (150 2725)(150 2775);
WIRE 17 -1 (150 2675)(150 2725);
WIRE 17 -1 (150 2625)(150 2675);
WIRE 17 -1 (150 2575)(150 2625);
WIRE 17 -1 (150 2525)(150 2575);
WIRE 17 -1 (150 2475)(150 2525);
WIRE 17 -1 (150 2425)(150 2475);
WIRE 17 -1 (150 2375)(150 2425);
WIRE 17 -1 (150 2325)(150 2375);
WIRE 17 -1 (150 2275)(150 2325);
WIRE 17 -1 (150 2225)(150 2275);
WIRE 17 -1 (150 2175)(150 2225);
WIRE 17 -1 (150 2125)(150 2175);
WIRE 17 -1 (150 2075)(150 2125);
WIRE 17 -1 (150 2025)(150 2075);
WIRE 17 -1 (150 1975)(150 2025);
WIRE 17 -1 (150 1925)(150 1975);
WIRE 17 -1 (150 1875)(150 1925);
WIRE 17 -1 (150 1825)(150 1875);
WIRE 17 -1 (150 1775)(150 1825);
WIRE 17 -1 (150 1725)(150 1775);
WIRE 17 -1 (150 1225)(150 1275);
WIRE 17 -1 (150 1275)(150 1325);
WIRE 17 -1 (150 1675)(150 1725);
WIRE 17 -1 (150 1625)(150 1675);
WIRE 17 -1 (150 1325)(150 1375);
WIRE 17 -1 (150 1375)(150 1425);
WIRE 17 -1 (150 1575)(150 1625);
WIRE 17 -1 (150 1525)(150 1575);
WIRE 17 -1 (150 1425)(150 1475);
WIRE 17 -1 (150 1475)(150 1525);
WIRE 17 -1 (-1500 3525)(-1500 3575);
WIRE 17 -1 (-1500 3575)(-1500 3625);
WIRE 17 -1 (-1500 3625)(-1500 3675);
WIRE 17 -1 (-1500 3675)(-1500 3725);
WIRE 17 -1 (-1500 3725)(-1500 3775);
WIRE 17 -1 (-1500 3775)(-1500 3825);
WIRE 17 -1 (-1500 3825)(-1500 3875);
WIRE 17 -1 (-1500 3875)(-1500 3925);
WIRE 17 -1 (-1500 3925)(-1500 3975);
WIRE 17 -1 (-1500 3975)(-1500 4025);
WIRE 17 -1 (-1500 4025)(-1500 4075);
WIRE 17 -1 (-1500 4075)(-1500 4125);
WIRE 17 -1 (-2050 4400)(-1500 4400);
FORCEPROP 2 LAST SIG_NAME M_A_MA<17:0>
J 0
(-2000 4410);
DISPLAY 0.617021 (-2000 4410);
PAINT ORANGE (-2000 4410);
WIRE 17 -1 (-1500 4125)(-1500 4175);
WIRE 17 -1 (-1500 4175)(-1500 4225);
WIRE 17 -1 (-1500 4375)(-1500 4400);
WIRE 17 -1 (-1500 4325)(-1500 4375);
WIRE 17 -1 (-1500 4225)(-1500 4275);
WIRE 17 -1 (-1500 4275)(-1500 4325);
WIRE 17 -1 (-1500 3450)(-2050 3450);
FORCEPROP 2 LAST SIG_NAME M_A_BA<1:0>
J 0
(-2025 3460);
DISPLAY 0.617021 (-2025 3460);
PAINT ORANGE (-2025 3460);
WIRE 17 -1 (-1500 3450)(-1500 3425);
WIRE 17 -1 (-1500 3375)(-1500 3425);
WIRE 17 -1 (-1500 3350)(-2050 3350);
FORCEPROP 2 LAST SIG_NAME M_A_BG<1:0>
J 0
(-2025 3360);
DISPLAY 0.617021 (-2025 3360);
PAINT ORANGE (-2025 3360);
WIRE 17 -1 (-1500 3275)(-1500 3325);
WIRE 17 -1 (-1500 3325)(-1500 3350);
WIRE 17 -1 (-1500 3200)(-2050 3200);
FORCEPROP 2 LAST SIG_NAME M_A_CLK_DP<3:0>
J 0
(-2025 3210);
DISPLAY 0.617021 (-2025 3210);
PAINT ORANGE (-2025 3210);
WIRE 17 -1 (-1500 3075)(-1500 3175);
WIRE 17 -1 (-1500 3175)(-1500 3200);
WIRE 17 -1 (-1700 3150)(-2050 3150);
FORCEPROP 2 LAST SIG_NAME M_A_CLK_DN<3:0>
J 0
(-2025 3160);
DISPLAY 0.617021 (-2025 3160);
PAINT ORANGE (-2025 3160);
WIRE 17 -1 (-1700 3125)(-1700 3025);
WIRE 17 -1 (-1700 3125)(-1700 3150);
WIRE 17 -1 (-1500 2900)(-2050 2900);
FORCEPROP 2 LAST SIG_NAME M_A_CS_N<7:0>
J 0
(-2025 2910);
DISPLAY 0.617021 (-2025 2910);
PAINT ORANGE (-2025 2910);
WIRE 17 -1 (-1500 2875)(-1500 2900);
WIRE 17 -1 (-1500 2825)(-1500 2875);
WIRE 17 -1 (-1500 2775)(-1500 2825);
WIRE 17 -1 (-1500 2725)(-1500 2775);
WIRE 17 -1 (-1500 2650)(-2050 2650);
FORCEPROP 2 LAST SIG_NAME M_A_CKE<3:0>
J 0
(-2025 2660);
DISPLAY 0.617021 (-2025 2660);
PAINT ORANGE (-2025 2660);
WIRE 17 -1 (-1500 2575)(-1500 2625);
WIRE 17 -1 (-1500 2625)(-1500 2650);
WIRE 17 -1 (-1500 2500)(-2050 2500);
FORCEPROP 2 LAST SIG_NAME M_A_ODT<3:0>
J 0
(-2025 2510);
DISPLAY 0.617021 (-2025 2510);
PAINT ORANGE (-2025 2510);
WIRE 17 -1 (-1500 2425)(-1500 2475);
WIRE 17 -1 (-1500 2475)(-1500 2500);
WIRE 17 -1 (-1500 1975)(-1500 2025);
WIRE 17 -1 (-1500 2025)(-1500 2075);
WIRE 17 -1 (-1500 2075)(-1500 2125);
WIRE 17 -1 (-1500 2125)(-1500 2175);
WIRE 17 -1 (-1500 2175)(-1500 2225);
WIRE 17 -1 (-1500 2350)(-2050 2350);
FORCEPROP 2 LAST SIG_NAME M_A_ECC<7:0>
J 0
(-2025 2360);
DISPLAY 0.617021 (-2025 2360);
PAINT ORANGE (-2025 2360);
WIRE 17 -1 (-1500 2325)(-1500 2350);
WIRE 17 -1 (-1500 2225)(-1500 2275);
WIRE 17 -1 (-1500 2275)(-1500 2325);
WIRE 16 -1 (-1200 3700)(-1400 3700);
WIRE 16 -1 (50 4150)(-200 4150);
WIRE 16 -1 (-1200 4300)(-1400 4300);
WIRE 16 -1 (2500 4800)(2100 4800);
WIRE 16 -1 (2500 4600)(2100 4600);
WIRE 16 -1 (2500 4500)(2100 4500);
WIRE 16 -1 (50 2850)(-200 2850);
WIRE 16 -1 (50 2700)(-200 2700);
WIRE 16 -1 (50 1850)(-200 1850);
WIRE 16 -1 (50 4350)(-200 4350);
WIRE 16 -1 (50 3950)(-200 3950);
WIRE 16 -1 (50 3900)(-200 3900);
WIRE 16 -1 (50 3850)(-200 3850);
WIRE 16 -1 (50 3800)(-200 3800);
WIRE 16 -1 (50 3750)(-200 3750);
WIRE 16 -1 (50 3700)(-200 3700);
WIRE 16 -1 (50 3650)(-200 3650);
WIRE 16 -1 (50 3600)(-200 3600);
WIRE 16 -1 (50 3500)(-200 3500);
WIRE 16 -1 (50 3450)(-200 3450);
WIRE 16 -1 (50 3400)(-200 3400);
WIRE 16 -1 (50 3350)(-200 3350);
WIRE 16 -1 (50 3300)(-200 3300);
WIRE 16 -1 (50 3000)(-200 3000);
WIRE 16 -1 (50 1600)(-200 1600);
WIRE 16 -1 (2500 3100)(2100 3100);
WIRE 16 -1 (2500 3200)(2100 3200);
WIRE 16 -1 (2500 3300)(2100 3300);
WIRE 16 -1 (2500 3400)(2100 3400);
WIRE 16 -1 (-1200 4150)(-1400 4150);
WIRE 16 -1 (50 4050)(-200 4050);
WIRE 16 -1 (-1200 3600)(-1400 3600);
WIRE 16 -1 (2500 3900)(2100 3900);
WIRE 16 -1 (-2750 1200)(-2650 1200);
WIRE 16 -1 (-1200 1200)(-2650 1200);
FORCEPROP 2 LAST SIG_NAME M_A_VREF
J 0
(-2548 1226);
DISPLAY 0.617021 (-2548 1226);
PAINT ORANGE (-2548 1226);
WIRE 16 -1 (-2650 1100)(-2650 1200);
WIRE 16 -1 (-2050 1050)(-1200 1050);
FORCEPROP 2 LAST SIG_NAME TP_CH_A_DIMM_A1_RFU_1
J 0
(-2000 1060);
DISPLAY 0.617021 (-2000 1060);
PAINT ORANGE (-2000 1060);
FORCEPROP 2 LASTPROP $XRERR UNIQUE?
J 0
(-2290 1050);
DISPLAY 0.638298 (-2290 1050);
PAINT MONO (-2290 1050);
DISPLAY INVISIBLE (-2290 1050);
WIRE 16 -1 (-2050 1100)(-1200 1100);
FORCEPROP 2 LAST SIG_NAME TP_CH_A_DIMM_A1_RFU_2
J 0
(-2000 1110);
DISPLAY 0.617021 (-2000 1110);
PAINT ORANGE (-2000 1110);
FORCEPROP 2 LASTPROP $XRERR UNIQUE?
J 0
(-2290 1100);
DISPLAY 0.638298 (-2290 1100);
PAINT MONO (-2290 1100);
DISPLAY INVISIBLE (-2290 1100);
WIRE 16 -1 (-2050 1000)(-1200 1000);
FORCEPROP 2 LAST SIG_NAME TP_CH_A_DIMM_A1_RFU_0
J 0
(-2000 1010);
DISPLAY 0.617021 (-2000 1010);
PAINT ORANGE (-2000 1010);
FORCEPROP 2 LASTPROP $XRERR UNIQUE?
J 0
(-2290 1000);
DISPLAY 0.638298 (-2290 1000);
PAINT MONO (-2290 1000);
DISPLAY INVISIBLE (-2290 1000);
WIRE 16 -1 (-1200 1350)(-2050 1350);
WIRE 16 -1 (-2050 1300)(-1200 1300);
FORCEPROP 2 LAST SIG_NAME SMB_DDR_ABC_VPP_SCL
J 0
(-2010 1310);
DISPLAY 0.617021 (-2010 1310);
PAINT ORANGE (-2010 1310);
WIRE 16 -1 (-1200 1650)(-2250 1650);
FORCEPROP 2 LAST SIG_NAME M_A_ACT_N
J 0
(-2200 1660);
DISPLAY 0.617021 (-2200 1660);
PAINT ORANGE (-2200 1660);
WIRE 16 -1 (-1200 1700)(-2275 1700);
FORCEPROP 2 LAST SIG_NAME M_A_ALERT_N
J 0
(-2225 1710);
DISPLAY 0.617021 (-2225 1710);
PAINT ORANGE (-2225 1710);
WIRE 16 -1 (-2050 900)(-1200 900);
FORCEPROP 2 LAST SIG_NAME FM_ADR_COMPLETE_ABC_N
J 0
(-2000 910);
DISPLAY 0.617021 (-2000 910);
PAINT ORANGE (-2000 910);
WIRE 16 -1 (-1650 2000)(-2375 2000);
FORCEPROP 2 LAST SIG_NAME FM_DIMM_EVENT_COD_N
J 0
(-2335 2006);
DISPLAY 0.617021 (-2335 2006);
PAINT ORANGE (-2335 2006);
WIRE 16 -1 (-1650 1750)(-1650 2000);
WIRE 16 -1 (-1650 1750)(-1200 1750);
WIRE 16 -1 (-1200 2000)(-1400 2000);
WIRE 16 -1 (-1200 1950)(-1400 1950);
WIRE 16 -1 (-1550 2300)(-2050 2300);
FORCEPROP 2 LAST SIG_NAME M_A_PAR
J 0
(-2025 2310);
DISPLAY 0.617021 (-2025 2310);
PAINT ORANGE (-2025 2310);
WIRE 16 -1 (-1200 1850)(-1550 1850);
WIRE 16 -1 (-1550 1850)(-1550 2300);
WIRE 16 -1 (-1600 2250)(-2050 2250);
FORCEPROP 2 LAST SIG_NAME M_ABC_RST_N
J 0
(-2025 2260);
DISPLAY 0.617021 (-2025 2260);
PAINT ORANGE (-2025 2260);
WIRE 16 -1 (-1200 1800)(-1600 1800);
WIRE 16 -1 (-1600 1800)(-1600 2250);
WIRE 16 -1 (-1200 3000)(-1600 3000);
WIRE 16 -1 (-1200 2250)(-1400 2250);
WIRE 16 -1 (-1200 2200)(-1400 2200);
WIRE 16 -1 (-1200 2150)(-1400 2150);
WIRE 16 -1 (-1200 2100)(-1400 2100);
WIRE 16 -1 (-1200 2050)(-1400 2050);
WIRE 16 -1 (-1200 2300)(-1400 2300);
WIRE 16 -1 (-1200 2400)(-1400 2400);
WIRE 16 -1 (-1200 2450)(-1400 2450);
WIRE 16 -1 (-1200 2550)(-1400 2550);
WIRE 16 -1 (-1350 2950)(-2050 2950);
FORCEPROP 2 LAST SIG_NAME M_A_C<2>
J 0
(-2000 2960);
DISPLAY 0.617021 (-2000 2960);
PAINT ORANGE (-2000 2960);
WIRE 16 -1 (-1350 2950)(-1350 2900);
WIRE 16 -1 (-1350 2900)(-1200 2900);
WIRE 16 -1 (-1200 3050)(-1400 3050);
WIRE 16 -1 (-1200 2850)(-1400 2850);
WIRE 16 -1 (-1200 2800)(-1400 2800);
WIRE 16 -1 (-1200 2750)(-1400 2750);
WIRE 16 -1 (-1200 2600)(-1400 2600);
WIRE 16 -1 (-1200 2700)(-1400 2700);
WIRE 16 -1 (-1200 3100)(-1600 3100);
WIRE 16 -1 (-1200 3400)(-1400 3400);
WIRE 16 -1 (-1200 3500)(-1400 3500);
WIRE 16 -1 (-1200 3550)(-1400 3550);
WIRE 16 -1 (-1200 3150)(-1400 3150);
WIRE 16 -1 (-1200 3250)(-1400 3250);
WIRE 16 -1 (-1200 3300)(-1400 3300);
WIRE 16 -1 (-1200 3350)(-1400 3350);
WIRE 16 -1 (-1200 3750)(-1400 3750);
WIRE 16 -1 (-1200 3800)(-1400 3800);
WIRE 16 -1 (-1200 3850)(-1400 3850);
WIRE 16 -1 (-1200 3900)(-1400 3900);
WIRE 16 -1 (-1200 3950)(-1400 3950);
WIRE 16 -1 (-1200 4000)(-1400 4000);
WIRE 16 -1 (-1200 4050)(-1400 4050);
WIRE 16 -1 (-1200 3650)(-1400 3650);
WIRE 16 -1 (-1200 4100)(-1400 4100);
WIRE 16 -1 (-1200 4350)(-1400 4350);
WIRE 16 -1 (-1200 4200)(-1400 4200);
WIRE 16 -1 (-1200 4250)(-1400 4250);
WIRE 16 -1 (50 2650)(-200 2650);
WIRE 16 -1 (50 2600)(-200 2600);
WIRE 16 -1 (50 4300)(-200 4300);
WIRE 16 -1 (50 4250)(-200 4250);
WIRE 16 -1 (50 4200)(-200 4200);
WIRE 16 -1 (50 4000)(-200 4000);
WIRE 16 -1 (50 3250)(-200 3250);
WIRE 16 -1 (50 3200)(-200 3200);
WIRE 16 -1 (50 3150)(-200 3150);
WIRE 16 -1 (50 2900)(-200 2900);
WIRE 16 -1 (50 2800)(-200 2800);
WIRE 16 -1 (50 2750)(-200 2750);
WIRE 16 -1 (50 2450)(-200 2450);
WIRE 16 -1 (50 2300)(-200 2300);
WIRE 16 -1 (50 2250)(-200 2250);
WIRE 16 -1 (50 2000)(-200 2000);
WIRE 16 -1 (50 1800)(-200 1800);
WIRE 16 -1 (50 1700)(-200 1700);
WIRE 16 -1 (50 1550)(-200 1550);
WIRE 16 -1 (50 1250)(-200 1250);
WIRE 16 -1 (50 1200)(-200 1200);
WIRE 16 -1 (50 2950)(-200 2950);
WIRE 16 -1 (50 3100)(-200 3100);
WIRE 16 -1 (50 2550)(-200 2550);
WIRE 16 -1 (50 2500)(-200 2500);
WIRE 16 -1 (50 1950)(-200 1950);
WIRE 16 -1 (50 2050)(-200 2050);
WIRE 16 -1 (50 4100)(-200 4100);
WIRE 16 -1 (50 3550)(-200 3550);
WIRE 16 -1 (50 1300)(-200 1300);
WIRE 16 -1 (50 1350)(-200 1350);
WIRE 16 -1 (50 1400)(-200 1400);
WIRE 16 -1 (50 1450)(-200 1450);
WIRE 16 -1 (50 3050)(-200 3050);
WIRE 16 -1 (50 2400)(-200 2400);
WIRE 16 -1 (50 2350)(-200 2350);
WIRE 16 -1 (50 1900)(-200 1900);
WIRE 16 -1 (50 2100)(-200 2100);
WIRE 16 -1 (50 1750)(-200 1750);
WIRE 16 -1 (50 2200)(-200 2200);
WIRE 16 -1 (50 2150)(-200 2150);
WIRE 16 -1 (50 1650)(-200 1650);
WIRE 16 -1 (50 1500)(-200 1500);
WIRE 16 -1 (2300 3250)(2100 3250);
WIRE 16 -1 (2300 3150)(2100 3150);
WIRE 16 -1 (2300 3550)(2100 3550);
WIRE 16 -1 (2300 3450)(2100 3450);
WIRE 16 -1 (2300 3350)(2100 3350);
WIRE 16 -1 (2500 3500)(2100 3500);
WIRE 16 -1 (2300 3750)(2100 3750);
WIRE 16 -1 (2300 3650)(2100 3650);
WIRE 16 -1 (2300 4050)(2100 4050);
WIRE 16 -1 (2300 3950)(2100 3950);
WIRE 16 -1 (2300 3850)(2100 3850);
WIRE 16 -1 (2500 4000)(2100 4000);
WIRE 16 -1 (2500 3800)(2100 3800);
WIRE 16 -1 (2500 3700)(2100 3700);
WIRE 16 -1 (2500 3600)(2100 3600);
WIRE 16 -1 (2300 4350)(2100 4350);
WIRE 16 -1 (2300 4250)(2100 4250);
WIRE 16 -1 (2300 4150)(2100 4150);
WIRE 16 -1 (2300 4550)(2100 4550);
WIRE 16 -1 (2300 4450)(2100 4450);
WIRE 16 -1 (2500 4400)(2100 4400);
WIRE 16 -1 (2500 4300)(2100 4300);
WIRE 16 -1 (2500 4200)(2100 4200);
WIRE 16 -1 (2500 4100)(2100 4100);
WIRE 16 -1 (2300 4850)(2100 4850);
WIRE 16 -1 (2300 4750)(2100 4750);
WIRE 16 -1 (2300 4650)(2100 4650);
WIRE 16 -1 (2500 4700)(2100 4700);
DOT 1 (950 1000);
DOT 1 (2750 3100);
DOT 1 (2750 3150);
DOT 1 (950 2000);
DOT 1 (-1400 1500);
DOT 1 (-1500 1550);
DOT 1 (-2650 1200);
DOT 1 (950 850);
DOT 1 (950 900);
DOT 1 (950 950);
DOT 1 (950 1050);
DOT 1 (950 1100);
DOT 1 (950 1150);
DOT 1 (950 1200);
DOT 1 (950 1250);
DOT 1 (950 1300);
DOT 1 (950 1350);
DOT 1 (950 1450);
DOT 1 (950 1550);
DOT 1 (950 1500);
DOT 1 (950 1600);
DOT 1 (950 1650);
DOT 1 (950 1700);
DOT 1 (950 1750);
DOT 1 (950 1800);
DOT 1 (950 1850);
DOT 1 (950 1950);
DOT 1 (950 1900);
DOT 1 (950 2050);
DOT 1 (950 2200);
DOT 1 (950 2350);
DOT 1 (950 2400);
DOT 1 (950 2450);
DOT 1 (950 2500);
DOT 1 (2750 1250);
DOT 1 (2750 1350);
DOT 1 (2750 1400);
DOT 1 (2750 1450);
DOT 1 (2750 1550);
DOT 1 (2750 1500);
DOT 1 (2750 1600);
DOT 1 (2750 1650);
DOT 1 (2750 1700);
DOT 1 (2750 1750);
DOT 1 (2750 1800);
DOT 1 (2750 1850);
DOT 1 (2750 1900);
DOT 1 (2750 1950);
DOT 1 (2750 2000);
DOT 1 (2300 2500);
DOT 1 (2750 2050);
DOT 1 (2750 2100);
DOT 1 (2750 2150);
DOT 1 (2750 2200);
DOT 1 (2750 2250);
DOT 1 (2750 2300);
DOT 1 (2750 2400);
DOT 1 (2750 2450);
DOT 1 (2750 2500);
DOT 1 (2750 2550);
DOT 1 (2750 2600);
DOT 1 (2750 2650);
DOT 1 (2750 2700);
DOT 1 (2750 2750);
DOT 1 (2750 2850);
DOT 1 (2750 2800);
DOT 1 (2750 2900);
DOT 1 (2750 2950);
DOT 1 (2750 3000);
DOT 1 (2750 3050);
DOT 1 (2750 3250);
DOT 1 (2750 3200);
DOT 1 (2750 3300);
DOT 1 (2750 3350);
DOT 1 (2750 3400);
DOT 1 (2750 3450);
DOT 1 (4150 1250);
DOT 1 (4150 1300);
DOT 1 (4150 1350);
DOT 1 (4150 1450);
DOT 1 (4150 1400);
DOT 1 (4150 1550);
DOT 1 (4150 1500);
DOT 1 (4150 1600);
DOT 1 (4150 1700);
DOT 1 (4150 1650);
DOT 1 (4150 1750);
DOT 1 (4150 1800);
DOT 1 (4150 1850);
DOT 1 (4150 1900);
DOT 1 (4150 1950);
DOT 1 (4150 2000);
DOT 1 (4150 2050);
DOT 1 (4150 2100);
DOT 1 (4150 2150);
DOT 1 (4150 2200);
DOT 1 (4150 2250);
DOT 1 (4150 2300);
DOT 1 (4150 2350);
DOT 1 (4150 2400);
DOT 1 (4150 2450);
DOT 1 (4150 2500);
DOT 1 (4150 2600);
DOT 1 (4150 2550);
DOT 1 (4150 2650);
DOT 1 (4150 2700);
DOT 1 (4150 2750);
DOT 1 (4150 2850);
DOT 1 (4150 2800);
DOT 1 (4150 2900);
DOT 1 (4150 2950);
DOT 1 (4150 3000);
DOT 1 (4150 3050);
DOT 1 (4150 3150);
DOT 1 (4150 3100);
DOT 1 (4150 3200);
DOT 1 (4150 3250);
DOT 1 (4150 3300);
DOT 1 (4150 3350);
DOT 1 (4150 3400);
DOT 1 (4150 3500);
DOT 1 (4150 3450);
DOT 1 (2750 1300);
DOT 1 (950 1400);
DOT 1 (2750 2350);
DOT 1 (2750 3500);
FORCENOTE
PVDDQ (SINGLE SIDE) CAP: 10UF X1, 22UF X50
(-2250 4750) 0;
DISPLAY LEFT (-2250 4750);
DISPLAY 1.021277 (-2250 4750);
PAINT PURPLE (-2250 4750);
FORCENOTE
PVDDQ (DOUBLE SIDE) CAP: 100UF X8, 47UF X41
(-2250 4700) 0;
DISPLAY LEFT (-2250 4700);
DISPLAY 1.021277 (-2250 4700);
PAINT PURPLE (-2250 4700);
FORCENOTE
CAP BETWEEN DIMM
(-2250 4925) 0;
DISPLAY LEFT (-2250 4925);
DISPLAY 1.276596 (-2250 4925);
PAINT PURPLE (-2250 4925);
FORCENOTE
PVPP CAP: 10UF X12
(-2250 4850) 0;
DISPLAY LEFT (-2250 4850);
DISPLAY 1.021277 (-2250 4850);
PAINT PURPLE (-2250 4850);
FORCENOTE
PVTT CAP: 100UF X2, 47UF X1
(-2250 4800) 0;
DISPLAY LEFT (-2250 4800);
DISPLAY 1.021277 (-2250 4800);
PAINT PURPLE (-2250 4800);
FORCENOTE
PLACE CAP NEAR DIMM CONNECTOR
(-2604 750) 0;
DISPLAY LEFT (-2604 750);
DISPLAY 1.021277 (-2604 750);
PAINT PURPLE (-2604 750);
FORCENOTE
SMBUS ADDR: 0XA2
(-3700 450) 0;
DISPLAY LEFT (-3700 450);
DISPLAY 1.361702 (-3700 450);
PAINT PURPLE (-3700 450);
QUIT
